# BARRELEYE_G2-FPDB_POST-PVT-X02-BOM-X05-20171123_Final.xls.xlsx — PWA BOM (bom)
| FOXCONN TECHNOLOGY GROUP |  |  |  |  |  |  |  |  |  |  |  |  |  |  |  |  |  |  |  |
| BILL OF MATERIAL |  |  |  |  |  |  |  |  |  |  |  |  |  |  |  |  |  |  |  |
| REV OF  BOM | X05 | CUSTOMER |  | <name> |  | CUSTOMER P/N |  | PWA P/N： | PWA DESCRIPTION |  |  |  | PRODUCT CODE |  |  | PWA  REV | X02 | DATE | 43060 |
| Sourcing (Single/Sole/Multi) | Critical Commodity (Y or N) | Component Class (1, 2, other) | Customer PSL (Y or N) | Line Item | Item Number | Foxconn P/N | Customer P/N | Part Description | Manufacturer  Full Name | Manufacturer  Part Number | Qty | RoHS Status | Location | CC Qual Build: | Qual by (Customer / ODM ?) | The Date of Change Part or Add 2nd Source | Configuration Identifier | Customer Comments | ODM Comments |
| Multi |  |  |  | 1 | 1 | 0101FGL00-000-G |  | PCB,Zaius-FPDB PVT-X01,OSP,Gre,6L,18.2623*7.025,G | GOLD CIRCUIT ELECTRONICS LTD. | 0101FGL00-000-G | 1 | G | PCB |  |  |  |  |  |  |
|  |  |  |  |  | 1 | 0101FGL00-000-G |  | PCB,Zaius-FPDB PVT-X01,OSP,Gre,6L,18.2623*7.025,G | ZHUHAI FOUNDER PRINTED CIRCUIT BOARD（HK） DEVELOPMENT LIMITED | 0101FGL00-000-G |  | G |  |  |  |  |  |  |  |
| Multi | ND | ND | Y(3) | 2 | 2 | 620103700-015-G | - | CAP,100nF,+/-10%,X7R,10V,G,SMD0402 | MURATA ELEC. NORTH AMERICA | GRM155R71A104K | 15 | G | C1,C2,C3,PHAC5,C18,C19,C22,C35,C2111,C2112,C2113,C2114,C2115,C2116,C2171 |  |  |  |  |  |  |
|  |  |  |  |  | 2 | 620103700-012-G |  | CAP,0.1uF,+/-10%,X7R,10V,G,SMD0402 | WALSIN TECHNOLOGY CORPORATION | 0402B104K100CT |  | G |  |  |  |  |  |  |  |
|  |  |  |  |  | 2 | 620103700-023-G |  | CAP,100nF,+/-10%,X7R,10V,G,SMD0402 | TAIYO ELECTRIC IND.CO.LTD | LMK105B7104KV-F |  | G |  |  |  |  |  |  |  |
|  |  |  |  |  | 2 | 620103700-026-G |  | CAP,100nF,+/-10%,X7R,10V,G,SMD0402 | SAMSUNG SEMICONDUCTOR | CL05B104KP5NNNC |  | G |  |  |  |  |  |  |  |
| Multi | ND | ND | Y(1) | 3 | 3 | 62010BN00-015-G | - | CAP,1uF,+/-10%,X5R,6.3V,G,SMD0402 | MURATA ELEC. NORTH AMERICA | GRM155R60J105K | 2 | G | C4,C11 |  |  |  |  |  |  |
|  |  |  |  |  | 3 | 62010BN00-023-G |  | CAP,1uF,+/-10%,X5R,6.3V,G,SMD0402 | TAIYO ELECTRIC IND.CO.LTD | JMK105BJ105KV |  | G |  |  |  |  |  |  |  |
|  |  |  |  |  | 3 | 62010BN00-026-G |  | CAP,1uF,+/-10%,X5R,6.3V,G,SMD0402 | SAMSUNG SEMICONDUCTOR | CL05A105KQ5NNNC |  | G |  |  |  |  |  |  |  |
|  |  |  |  |  | 3 | 62010BN00-011-G |  | CAP,1uF,+/-10%,X5R,6.3V,G,SMD0402 | YAGEO CORPORATION COMPONENT | CC0402KRX5R5BB105 |  | G |  |  |  |  |  |  |  |
|  |  |  |  |  | 3 | 62010BN00-012-G |  | CAP,1uF,+/-10%,X5R,6.3V,G,SMD0402 | WALSIN TECHNOLOGY CORPORATION | 0402X105K6R3CT |  | G |  |  |  |  |  |  |  |
| Multi | ND | ND | Y(3) | 4 | 4 | 620106200-015-G | - | CAP,10nF,+/-10%,X7R,16V,G,SMD0402 | MURATA ELEC. NORTH AMERICA | GRM155R71C103K | 2 | G | C5,C12 |  |  |  |  |  |  |
|  |  |  |  |  | 4 | 620106200-012-G |  | CAP,10nF,+/-10%,X7R,16V,G,SMD0402 | WALSIN TECHNOLOGY CORPORATION | 0402B103K160CT |  | G |  |  |  |  |  |  |  |
|  |  |  |  |  | 4 | 620106200-026-G |  | CAP,10nF,+/-10%,X7R,16V,G,SMD0402 | SAMSUNG SEMICONDUCTOR | CL05B103KO5NNNC |  | G |  |  |  |  |  |  |  |
|  |  |  |  |  | 4 | 620106200-023-G |  | CAP,10nF,+/-10%,X7R,16V,G,SMD0402 | TAIYO ELECTRIC IND.CO.LTD | EMK105B7103KV-F |  | G |  |  |  |  |  |  |  |
| Multi | Y | 2 | Y(3) | 5 | 5 | 620101T02-015-G | - | CAP,100nF,+/-10%,X7R,16V,G,SMD0402 | MURATA ELEC. NORTH AMERICA | GRM155R71C104K | 17 | G | C6,C7,C9,PSRC10,C13,C14,C16,C20,C21,C38,C39,C46,C362,C394,C2107,C2108,C2109 |  |  |  |  |  |  |
|  |  |  |  |  | 5 | 620101T00-012-G |  | CAP,100nF,+/-10%,X7R,16V,G,SMD0402 | WALSIN TECHNOLOGY CORPORATION | 0402B104K160CT |  | G |  |  |  |  |  |  |  |
|  |  |  |  |  | 5 | 620101T00-026-G |  | CAP,100nF,+/-10%,X7R,16V,G,SMD0402 | SAMSUNG SEMICONDUCTOR | CL05B104KO5NNNC |  | G |  |  |  |  |  |  |  |
|  |  |  |  |  | 5 | 620101T00-015-G |  | CAP,100nF,+/-10%,X7R,16V,G,SMD0402 | MURATA ELEC. NORTH AMERICA | GRM155R71C104KA88D |  | G |  |  |  |  |  |  |  |
| Multi | Y |  | Y(1) | 6 | 6 | 620130V00-015-G |  | CAP,10uF,+/-20%,X6S,16V,G,SMD0603 | MURATA ELEC. NORTH AMERICA | GRM188C81C106MA73D | 10 | G | C8,C10,C15,C17,C40,C43,C47,C50,C53,C56 |  |  |  |  |  |  |
|  |  |  |  |  | 6 | 620130V00-023-G |  | CAP,10uF,+/-20%,X6S,16V,G,SMD0603 | TAIYO ELECTRIC IND.CO.LTD | EMK107BC6106MA-T |  | G |  |  |  |  |  |  |  |
| Multi | Y | 2 | Y(3) | 7 | 7 | 620103K00-015-G | - | CAP,1nF,+/-10%,X7R,50V,G,SMD0402 | MURATA ELEC. NORTH AMERICA | GRM155R71H102K | 3 | G | PHAC2,C36,C37 |  |  |  |  |  |  |
|  |  |  |  |  | 7 | 620103K00-012-G |  | CAP,1nF,+/-10%,X7R,50V,G,SMD0402 | WALSIN TECHNOLOGY CORPORATION | 0402B102K500CT |  | G |  |  |  |  |  |  |  |
|  |  |  |  |  | 7 | 620103K00-026-G |  | CAP,1nF,+/-10%,X7R,50V,G,SMD0402 | SAMSUNG SEMICONDUCTOR | CL05B102KB5NNNC |  | G |  |  |  |  |  |  |  |
|  |  |  |  |  | 7 | 620103K00-023-G |  | CAP,1nF,+/-10%,X7R,50V,G,SMD0402 | TAIYO ELECTRIC IND.CO.LTD | UMK105B7102KV-F |  | G |  |  |  |  |  |  |  |
| Multi | ND | ND | Y(3) | 8 | 8 | 620100L00-015-G | - | CAP,22pF,+/-5%,NPO(C0G),50V,G,SMD0402 | MURATA ELEC. NORTH AMERICA | GRM1555C1H220J | 12 | G | C41,C42,C44,C45,C48,C49,C51,C52,C54,C55,C57,C58 |  |  |  |  |  |  |
|  |  |  |  |  | 8 | 620100L08-012-G |  | CAP,22pF,+/-5%,NPO(C0G),50V,G,SMD0402 | WALSIN TECHNOLOGY CORPORATION | 0402N220J500CT |  | G |  |  |  |  |  |  |  |
|  |  |  |  |  | 8 | 620100L00-026-G |  | CAP,22pF,+/-5%,NPO(C0G),50V,G,SMD0402 | SAMSUNG SEMICONDUCTOR | CL05C220JB5NNNC |  | G |  |  |  |  |  |  |  |
|  |  |  |  |  | 8 | 620100L00-023-G |  | CAP,22pF,+/-5%,NPO(C0G),50V,G,SMD0402 | TAIYO ELECTRIC IND.CO.LTD | UMK105CG220JV-F |  | G |  |  |  |  |  |  |  |
| Multi | Y |  | Y(1) | 9 | 9 | 62012FR00-015-G |  | CAP,10uF,+/-20%,X5R,25V,G,SMD0603 | MURATA ELEC. NORTH AMERICA | GRM188R61E106M | 2 | G | C398,C399 |  |  |  |  |  |  |
|  |  |  |  |  | 9 | 62012FR00-023-G |  | CAP,10uF,+/-20%,X5R,25V,G,SMD0603 | TAIYO ELECTRIC IND.CO.LTD | TMK107BBJ106MA-T |  | G |  |  |  |  |  |  |  |
|  |  |  |  |  | 9 | 62012FR00-026-G |  | CAP,10uF,+/-20%,X5R,25V,G,SMD0603 | SAMSUNG SEMICONDUCTOR | CL10A106MA8NRNC |  | G |  |  |  |  |  |  |  |
| Multi |  |  | Y(3) | 10 | 10 | 620100D00-015-G |  | CAP,100nF,+/-10%,X7R,16V,G,SMD0603 | MURATA ELEC. NORTH AMERICA | GRM188R71C104K | 1 | G | C400 |  |  |  |  |  |  |
|  |  |  |  |  | 10 | 620100D00-012-G |  | CAP,100nF,+/-10%,X7R,16V,G,SMD0603 | WALSIN TECHNOLOGY CORPORATION | 0603B104K160CT |  | G |  |  |  |  |  |  |  |
|  |  |  |  |  | 10 | 620100D00-026-G |  | CAP,100nF,+/-10%,X7R,16V,G,SMD0603 | SAMSUNG SEMICONDUCTOR | CL10B104KO8NNNC |  | G |  |  |  |  |  |  |  |
| Multi | ND | ND | Y(1) | 11 | 11 | 62012A400-015-G | - | CAP,100nF,+/-10%,X7R,25V,G,SMD0402 | MURATA ELEC. NORTH AMERICA | GRM155R71E104KE14D | 6 | G | PSRC1,PSUC3,PEUC3,PSRC6,PHAC19,C2117 |  |  |  |  |  |  |
|  |  |  |  |  | 11 | 62012A400-023-G |  | CAP,100nF,+/-10%,X7R,25V,G,SMD0402 | TAIYO ELECTRIC IND.CO.LTD | TMK105B7104KV-FR |  | G |  |  |  |  |  |  |  |
|  |  |  |  |  | 11 | 62012A400-026-G |  | CAP,100nF,+/-10%,X7R,25V,G,SMD0402 | SAMSUNG SEMICONDUCTOR | CL05B104KA5NNNC |  | G |  |  |  |  |  |  |  |
|  |  |  |  |  | 11 | 62012A400-012-G |  | CAP,100nF,+/-10%,X7R,25V,G,SMD0402 | WALSIN TECHNOLOGY CORPORATION | 0402B104K250CT |  | G |  |  |  |  |  |  |  |
| Multi | ND | ND | Y(3) | 12 | 12 | 62010VD00-015-G |  | CAP,100nF,+/-10%,X7R,100V,G,SMD0603 | MURATA ELEC. NORTH AMERICA | GRM188R72A104K | 2 | G | PHAC14,C2118 |  |  |  |  |  |  |
|  |  |  |  |  | 12 | 62010VD00-026-G |  | CAP,100nF,+/-10%,X7R,100V,G,SMD0603 | SAMSUNG SEMICONDUCTOR | CL10B104KC8NNNC |  | G |  |  |  |  |  |  |  |
| Multi | Y | 2 | Y(3) | 13 | 13 | 620108000-015-G | - | CAP,100pF,+/-5%,NPO(C0G),50V,G,SMD0402 | MURATA ELEC. NORTH AMERICA | GRM1555C1H101J | 1 | G | C2168 |  |  |  |  |  |  |
|  |  |  |  |  | 13 | 62010800A-012-G |  | CAP,100pF,+/-5%,NPO(C0G),50V,G,SMD0402 | WALSIN TECHNOLOGY CORPORATION | 0402N101J500CT |  | G |  |  |  |  |  |  |  |
|  |  |  |  |  | 13 | 620108000-026-G |  | CAP,100pF,+/-5%,NPO(C0G),50V,G,SMD0402 | SAMSUNG SEMICONDUCTOR | CL05C101JB5NNNC |  | G |  |  |  |  |  |  |  |
|  |  |  |  |  | 13 | 620108000-023-G |  | CAP,100pF,+/-5%,NPO(C0G),50V,G,SMD0402 | TAIYO ELECTRIC IND.CO.LTD | UMK105CG101JV-F |  | G |  |  |  |  |  |  |  |
| Multi | Y |  | Y(1) | 14 | 14 | 62010DW00-015-G |  | CAP,10uF,+/-10%,X7R,16V,G,SMD1206 | MURATA ELEC. NORTH AMERICA | GRM31CR71C106K | 1 | G | C2170 |  |  |  |  |  |  |
|  |  |  |  |  | 14 | 62010DW00-026-G |  | CAP,10uF,+/-10%,X7R,16V,G,SMD1206 | SAMSUNG SEMICONDUCTOR | CL31B106KOHNNNE |  | G |  |  |  |  |  |  |  |
|  |  |  |  |  | 14 | 62010DW00-023-G |  | CAP,10uF,+/-10%,X7R,16V,G,SMD1206 | TAIYO ELECTRIC IND.CO.LTD | EMK316B7106KL-TD |  | G |  |  |  |  |  |  |  |
| Multi | ND | ND | N | 15 | 15 | 520100200-237-G | - | DIODE,Switching,1N4148W-7-F,100V,0.15A,G,SOD123-2,SMD | DIODES INEORPORATION | 1N4148W-7-F | 13 | G | D1,D2,D3,D4,D5,PHAD6,D6,D7,D8,D9,D10,D11,D12 |  |  |  |  |  |  |
|  |  |  |  |  | 15 | 520102P00-031-G |  | DIODE,Switching,BAS16H,100V,0.5A,G,SOD123F-2,SMD | NXP SEMICONDUCTORS | BAS16H |  | G |  |  |  |  |  |  |  |
| Multi | ND |  | N | 16 | 16 | 520308D00-237-G |  | DIODE,Schottky Rectifier,1N5819HW-7-F,40V,1A,G,SOD123-2,SMD | DIODES INCORPORATION | 1N5819HW-7-F | 1 | G | D33 |  |  |  |  |  |  |
|  |  |  |  |  | 16 | 520318S00-223-G |  | Diode,Schottky,MBR140SFT3G,40V,1A,G,SOD-123FL-2,SMD | ON SEMICONDUCTOR CORP | MBR140SFT3G |  | G |  |  |  |  |  |  |  |
|  |  |  |  |  | 16 | 52030P100-223-G |  | Diode,Schottky,MBR140SFT1G,40V,1A,SOD-123FL,2P,G | ON SEMICONDUCTOR CORP | MBR140SFT1G |  | G |  |  |  |  |  |  |  |
| Multi | ND | ND | N | 17 | 17 | 520401Y00-237-G | - | DIODE,Zener,BZT52C3V6-7-F,3.6V,5mA,G,SOD123-2,SMD | DIODES INEORPORATION | BZT52C3V6-7-F | 1 | G | D34 |  |  |  |  |  |  |
|  |  |  |  |  | 17 | 520407600-223-G |  | Diode,ZENER,MMSZ3V6T1G,3.6V,5mA,SOD-123,2P,G | ON SEMICONDUCTOR CORP | MMSZ3V6T1G |  | G |  |  |  |  |  |  |  |
| Single | ND | ND | Y(1) | 18 | 18 | 730101C00-086-G |  | Fuse,Slow blow,125V,30A,G,SMD | LITTELFUSE FAR EAST PTE LTD | 0456030.ER | 3 | G | FS1,FS2,FS10 |  |  |  |  |  |  |
| Multi | ND |  | Y(1) | 19 | 19 | 0438005.WRGT |  | Fuse,Fast acting,32V,5A,G,SMD0603 | LITTELFUSE FAR EAST PTE LTD | 0438005.WRGT | 6 | G | FS4,FS5,FS6,FS7,FS8,FS9 |  |  |  |  |  |  |
|  |  |  |  |  | 19 | 730103M00-086-G |  | Fuse,Fast acting,32V,5A,G,SMD0603 | LITTELFUSE FAR EAST PTE LTD | 0438005.WR |  | G |  |  |  |  |  |  |  |
|  |  |  |  |  | 19 | 730103M00-088-G |  | Fuse,Fast acting,32V,5A,SMD0603,G | COOPER BUSSMANN, INC. | CC06H5A-TR |  | G |  |  |  |  |  |  |  |
| Multi | N | Other | N | 20 | 20 | 72010KB01-016-G | - | FB,330 Ohm@100MHz,+/-25%,2.5A,50mOhm,G,SMD0805 | TDK ELECTRONICS EUROPE GMBH | MPZ2012S331AT | 6 | G | L1,L2,L3,L4,L5,L6 |  |  |  |  |  |  |
|  |  |  |  |  | 20 | 720100W00-015-G |  | FB,330 Ohm@100MHz,+/-25%,1.5A,90mOhm,G,SMD0805 | MURATA ELEC. NORTH AMERICA | BLM21PG331SN1D |  | G |  |  |  |  |  |  |  |
|  |  |  |  |  | 20 | 720104R00-023-G |  | FB,330 Ohm@100MHz,+/-25%,1.8A,80mOhm,G,SMD0805 | TAIYO ELECTRIC IND.CO.LTD | FBMH2012HM331-T |  | G |  |  |  |  |  |  |  |
| Multi | N |  | Y(2) | 21 | 21 | 62111CS00-024-G |  | ECAP,68uF,+/-20%,100V,105C,G,SMD12.5*13.5,ESR<=320mOhm | PANASONIC INDUSTRIAL CO.,LTD. | EEVFK2A680Q | 4 | G | PSUCE1,PEUCE1,PSUCE2,PEUCE2 |  |  |  |  |  |  |
|  |  |  |  |  | 21 | 62111RR00-025-G |  | ECAP,AL,Low ESR(LESR),68uF,+/-20%,100V,105_x0003_,500mOhm,SMD,12.5*13.5,G | KEMET ELECTRONICS CORPORATION | EXV686M100A9RAA |  | G |  |  |  |  |  |  |  |
|  |  |  |  |  | 21 | 62111SK00-021-G |  | ECAP,AL,Low ESR(LESR),68uF,+/-20%,100V,105_x0003_,330mOhm,SMD,12.5*13.5,G | NIPPON CHEMI-CON CORPORATION | EMVY101ARA680MKE0S |  | G |  |  |  |  |  |  |  |
| Multi | N |  | N | 22 | 22 | 62120HJ00-022-G |  | ECAP,SPEA,270uF,+/-20%,16V,105C,G,SMD6.3X9.9,ESR<=8mOhm | SANYO ELECTRIC CO., LTD. | 16SVPG270M | 2 | G | PSUCE4,PEUCE4 |  |  |  |  |  |  |
|  |  |  |  |  | 22 | 62120LS00-021-G |  | ECAP,Solid Polymer Electrolytic Aluminium Capacitor (SPEA),Low ESR(LESR),270uF,+/-20%,16V,105_x0003_,10mOhm,SMD,6.3*7.7,G | NIPPON CHEMI-CON CORPORATION | APXJ160ARA271MF80J |  | G |  |  |  |  |  |  |  |
| Multi | N |  | Y(1) | 23 | 23 | 62011J601-015-G |  | CAP,2.2uF,+/-10%,X7R,100V,G,SMD1210 | MURATA ELEC. NORTH AMERICA | GRM32ER72A225K | 4 | G | PSUC1,PEUC1,PSUC2,PEUC2 |  |  |  |  |  |  |
|  |  |  |  |  | 23 | 62011J600-026-G |  | CAP,2.2uF,+/-10%,X7R,100V,G,SMD1210 | SAMSUNG SEMICONDUCTOR | CL32B225KCJSNNE |  | G |  |  |  |  |  |  |  |
| Multi | ND | ND | Y(1) | 24 | 24 | 62011F100-015-G |  | CAP,1uF,+/-10%,X7R,25V,G,SMD0603 | MURATA ELEC. NORTH AMERICA | GRM188R71E105K | 2 | G | PSUC4,PEUC4 |  |  |  |  |  |  |
|  |  |  |  |  | 24 | 62011F100-023-G |  | CAP,1uF,+/-10%,X7R,25V,G,SMD0603 | TAIYO ELECTRIC IND.CO.LTD | TMK107B7105KA-T |  | G |  |  |  |  |  |  |  |
|  |  |  |  |  | 24 | 62011F100-026-G |  | CAP,1uF,+/-10%,X7R,25V,G,SMD0603 | SAMSUNG SEMICONDUCTOR | CL10B105KA8NNNC |  | G |  |  |  |  |  |  |  |
| Single | ND |  | Y(1) | 25 | 25 | 62012T500-015-G |  | CAP,22uF,+/-20%,X7S,25V,G,SMD1206 | MURATA ELEC. NORTH AMERICA | GRM31CC71E226ME11L | 14 | G | PSRC2,PSUC5,PEUC5,PSUC6,PEUC6,PSUC7,PEUC7,PSUC8,PEUC8,PSUC9,PEUC9,PSUC10,PEUC10,PSRC17 |  |  |  |  |  |  |
| Multi | N |  | Y(4) | 26 | 26 | 610119C00-017-G |  | RES,130KOhm,+/-1%,1/16W,G,SMD0402 | KOA SPEER ELECTRONICS, INC. | RK73H1ETTP1303F | 2 | G | PEUR1,PSUR2 |  |  |  |  |  |  |
|  |  |  |  |  | 26 | 610119C00-011-G |  | RES,130KOhm,+/-1%,1/16W,G,SMD0402 | YAGEO CORPORATION COMPONENT | RC0402FR-07130KL |  | G |  |  |  |  |  |  |  |
|  |  |  |  |  | 26 | 610119C00-012-G |  | RES,130KOhm,+/-1%,1/16W,G,SMD0402 | WALSIN TECHNOLOGY CORPORATION | WR04X1303FTL |  | G |  |  |  |  |  |  |  |
|  |  |  |  |  | 26 | 610119C00-044-G |  | RES,130KOhm,+/-1%,1/16W,G,SMD0402 | TA-I TECHNOLOGY CO., LTD | RM04FTN1303 |  | G |  |  |  |  |  |  |  |
| Multi | N | ND | Y(4) | 27 | 27 | 61010G500-017-G | - | RES,10KOhm,+/-1%,1/16W,G,SMD0402 | KOA SPEER ELECTRONICS, INC. | RK73H1ETTP1002F | 18 | G | PEUR2,PSRR6,R23,PHAR39,R119,R121,R131,R133,R138,R159,R162,R172,R174,R183,R185,R195,R197,R234 |  |  |  |  |  |  |
|  |  |  |  |  | 27 | 61010G500-012-G |  | RES,10KOhm,+/-1%,1/16W,G,SMD0402 | WALSIN TECHNOLOGY CORPORATION | WR04X1002FTL |  | G |  |  |  |  |  |  |  |
|  |  |  |  |  | 27 | 61010G500-011-G |  | RES,10KOhm,+/-1%,1/16W,G,SMD0402 | YAGEO CORPORATION COMPONENT | RC0402FR-0710KL |  | G |  |  |  |  |  |  |  |
|  |  |  |  |  | 27 | 61010G500-044-G |  | RES,10KOhm,+/-1%,1/16W,G,SMD0402 | TA-I TECHNOLOGY CO., LTD. | RM04FTN1002 |  | G |  |  |  |  |  |  |  |
|  |  |  |  |  | 27 | 61010G500-029-G |  | RES,10KOhm,+/-1%,1/16W,G,SMD0402 | VISHAY ENTER TECHNO LOGY.INC | CRCW040210K0FKED |  | G |  |  |  |  |  |  |  |
|  |  |  |  |  | 27 | 61010G500-024-G |  | RES,10KOhm,+/-1%,1/16W,G,SMD0402 | PANASONIC INDUSTRIAL CO.,LTD. | ERJ2RKF1002X |  | G |  |  |  |  |  |  |  |
| Multi | N | ND | Y(4) | 28 | 28 | 610107A00-017-G | - | RES,0 Ohm,+/-5%,1/16W,G,SMD0402 | KOA SPEER ELECTRONICS, INC. | RK73Z1ETTP | 65 | G | R1,PEUR4,PSRR8,R9,PSRR9,R10,PHAR11,PHAR12,PSRR15,PSRR18,PHAR24,PHAR25,R30,R31,PHAR31,PHAR32,PHAR34,R51,R52,R56,R57,R70,R71,R84,R85,R123,R135,R139,R140,R161,R171,R199,R494,R499,PSUR500,PEUR500,PSUR501,PEUR501,R1478,R1491,R1775,R1780,R1782,R1784,R1785,R1786,R1787,R1788,R1789,R1790,R1791,R1792,R1793,R1794,R1795,R1796,R1797,R1798,R1799,R1800,R1801,R1802,R1813,R1827,PHAR33 |  |  |  |  |  |  |
|  |  |  |  |  | 28 | 610107A00-012-G |  | RES,0 Ohm,+/-5%,1/16W,G,SMD0402 | WALSIN TECHNOLOGY CORPORATION | WR04X000PTL |  | G |  |  |  |  |  |  |  |
|  |  |  |  |  | 28 | 610107A00-011-G |  | RES,0 Ohm,+/-5%,1/16W,G,SMD0402 | YAGEO CORPORATION COMPONENT | RC0402JR-070RL |  | G |  |  |  |  |  |  |  |
|  |  |  |  |  | 28 | 610107A00-044-G |  | RES,0 Ohm,+/-5%,1/16W,G,SMD0402 | TA-I TECHNOLOGY CO., LTD. | RM04JTN0 |  | G |  |  |  |  |  |  |  |
|  |  |  |  |  | 28 | 610107A00-024-G |  | RES,0 Ohm,+/-5%,1/16W,G,SMD0402 | PANASONIC INDUSTRIAL CO.,LTD. | ERJ2GE0R00X |  | G |  |  |  |  |  |  |  |
|  |  |  |  |  | 28 | 610107A00-029-G |  | RES,0 Ohm,+/-5%,1/16W,G,SMD0402 | VISHAY ENTER TECHNO LOGY.INC | CRCW04020000Z0ED |  | G |  |  |  |  |  |  |  |
| Multi | N |  | N | 29 | 29 | 880302300-065-G |  | Converter,input 40V~60V,600W,G,Q54SJ12050NNDH | DELTA ELECTRONICS INDUSTRIAL CO.,LTD | Q54SJ12050NNDH | 2 | G | PSUU1,PEUU1 |  |  |  |  |  |  |
|  |  |  |  |  | 29 | 880302100-065-G |  | Converter,input 40V~60V,600W,G,Q54SH12050NNDH | DELTA ELECTRONICS INDUSTRIAL CO.,LTD | Q54SH12050NNDH |  | G |  |  |  |  |  |  |  |
| Multi | Y |  | Y(1) | 30 | 30 | 620131D00-015-G |  | CAP,1uF,+/-10%,X6S,16V,G,SMD0402 | MURATA ELEC. NORTH AMERICA | GRM155C81C105KE11J | 2 | G | PHAC1,PHAC7 |  |  |  |  |  |  |
|  |  |  |  |  | 30 | 620131D00-023-G |  | CAP,1uF,+/-10%,X6S,16V,G,SMD0402 | TAIYO ELECTRIC IND.CO.LTD | EMK105C6105KV-F |  | G |  |  |  |  |  |  |  |
| Multi | ND |  | Y(1) | 31 | 31 | 620133600-015-G |  | CAP,1nF,+/-5%,X7R,100V,G,SMD0805 | MURATA ELEC. NORTH AMERICA | GRM219R72A102JA01D | 1 | G | PHAC3 |  |  |  |  |  |  |
|  |  |  |  |  | 31 | 620133600-012-G |  | CAP,1nF,+/-5%,X7R,100V,G,SMD0805 | WALSIN TECHNOLOGY CORPORATION | 0805B102J101CT |  | G |  |  |  |  |  |  |  |
|  |  |  |  |  | 31 | 620133600-026-G |  | CAP,1nF,+/-5%,X7R,100V,G,SMD0805 | SAMSUNG SEMICONDUCTOR | CL21B102JCANNNC |  | G |  |  |  |  |  |  |  |
| Multi | Y | 2 | Y(3) | 32 | 32 | 62010G800-015-G | - | CAP,22nF,+/-10%,X7R,16V,G,SMD0402 | MURATA ELEC. NORTH AMERICA | GRM155R71C223K | 1 | G | PHAC4 |  |  |  |  |  |  |
|  |  |  |  |  | 32 | 62010G800-012-G |  | CAP,22nF,+/-10%,X7R,16V,G,SMD0402 | WALSIN TECHNOLOGY CORPORATION | 0402B223K160CT |  | G |  |  |  |  |  |  |  |
|  |  |  |  |  | 32 | 62010G800-026-G |  | CAP,22nF,+/-10%,X7R,16V,G,SMD0402 | SAMSUNG SEMICONDUCTOR | CL05B223KO5NNNC |  | G |  |  |  |  |  |  |  |
|  |  |  |  |  | 32 | 62010G800-023-G |  | CAP,22nF,+/-10%,X7R,16V,G,SMD0402 | TAIYO ELECTRIC IND.CO.LTD | EMK105B7223KV-F |  | G |  |  |  |  |  |  |  |
| Multi | ND |  | Y(1) | 33 | 33 | 620135500-015-G |  | CAP,39nF,+/-10%,X7R,100V,G,SMD0805 | MURATA ELEC. NORTH AMERICA | GRM21BR72A393KA01L | 1 | G | PHAC18 |  |  |  |  |  |  |
|  |  |  |  |  | 33 | 620135500-012-G |  | CAP,39nF,+/-10%,X7R,100V,G,SMD0805 | WALSIN TECHNOLOGY CORPORATION | 0805B393K101CT |  | G |  |  |  |  |  |  |  |
| Multi | ND |  | N | 34 | 34 | 52170KE00-086-G |  | TVS Diode,SMCJ64A,G,DO-214AB-2,SMD | LITTELFUSE FAR EAST PTE LTD | SMCJ64A | 1 | G | PHAD1 |  |  |  |  |  |  |
|  |  |  |  |  | 34 | 52170ER00-237-G |  | TVS Diode,SMCJ64A-13-F,SMC/DO-214AB,2P,G | DIODES INCORPORATION | SMCJ64A-13-F |  | G |  |  |  |  |  |  |  |
| Single | N |  | N | 35 | 35 | 52030YE00-223-G |  | DIODE,Schottky,MBR5H100MFST1G,100V,5A,G,SO8FL-8,SMD | ON SEMICONDUCTOR CORP | MBR5H100MFST1G | 1 | G | PHAD2 |  |  |  |  |  |  |
| Multi | Y | ND | N | 36 | 36 | 52040EC00-237-G |  | DIODE,Zener,MMSZ5246B-7-F,16V,7.8mA,G,SOD123-2,SMD | DIODES INEORPORATION | MMSZ5246B-7-F | 1 | G | PHAD3 |  |  |  |  |  |  |
|  |  |  |  |  | 36 | 52040B500-223-G |  | DIODE,Zener,MMSZ5246BT1G,16V,7.8mA,G,SOD123-2,SMD | ON SEMICONDUCTOR CORP | MMSZ5246BT1G |  | G |  |  |  |  |  |  |  |
|  |  |  |  |  | 36 | 52040EY00-031-G |  | Diode,ZENER,BZT52H-C16,17.1V,5mA,G,SOD123F-2,SMD | NXP SEMICONDUCTORS | BZT52H-C16 |  | G |  |  |  |  |  |  |  |
| Multi | N |  | N | 37 | 37 | 51031VY00-031-G |  | MOS N,PSMN4R8-100BSE,100V,120A,4.8m@10V,G,SOT404-3,SMD | NXP SEMICONDUCTORS | PSMN4R8-100BSE | 3 | G | PHAQ1,PHAQ2,PHAQ3 |  |  |  |  |  |  |
|  |  |  |  |  | 37 | 51032JY00-029-G |  | MOS N,SUM70040E-GE3,100V,120A,G,TO-263-3,SMD | VISHAY ENTER TECHNO LOGY.INC | SUM70040E-GE3 |  | G |  |  |  |  |  |  |  |
|  |  |  |  |  | 37 | 51032HE00-185-G |  | MOS N,FDB047N10,100V,120A,3.9m@10V,G,TO263-3,SMD | FAIRCHILD SEMICONDUCTOR CORP | FDB047N10 |  | G |  |  |  |  |  |  |  |
| Multi | ND |  | N | 38 | 38 | 51020A000-031-G |  | TRANS P,PBHV9115T,150V,1A,G,SOT23-3,SMD | NXP SEMICONDUCTORS | PBHV9115T | 1 | G | PHAQ4 |  |  |  |  |  |  |
|  |  |  |  |  | 38 | 51020BJ00-185-G |  | Trans PNP,MMBT5401,-150V,-600mA,G,SOT-23-3,SMD | FAIRCHILD SEMICONDUCTOR CORP | MMBT5401 |  | G |  |  |  |  |  |  |  |
|  |  |  |  |  | 38 | 510204N00-237-G |  | Trans PNP,MMBT5401-7-F,-150V,-600mA,SOT-23,3P,G | DIODES INCORPORATION | MMBT5401-7-F |  | G |  |  |  |  |  |  |  |
| Single | N |  | N | 39 | 39 | 51032D100-237-G |  | MOS N,DMN10H220L-7,100V,1.6A,220m@10V,G,SOT-23-3,SMD | DIODES INCORPORATION | DMN10H220L-7 | 2 | G | PHAQ5,PHAQ9 |  |  |  |  |  |  |
| Multi | ND | ND | Y(3) | 40 | 40 | 510100W00-237-G | - | TRANS N,MMBT3904-7-F,40V,0.2A,G,SOT23-3,SMD | DIODES INEORPORATION | MMBT3904-7-F | 1 | G | PHAQ8 |  |  |  |  |  |  |
|  |  |  |  |  | 40 | 510101700-185-G |  | TRANS N,MMBT3904,40V,0.2A,G,SOT23-3,SMD | FAIRCHILD SEMICONDUCTOR CORP | MMBT3904 |  | G |  |  |  |  |  |  |  |
|  |  |  |  |  | 40 | 510100800-223-G |  | TRANS N,MMBT3904LT1G,40V,0.2A,G,SOT23-3,SMD | ON SEMICONDUCTOR CORP | MMBT3904LT1G |  | G |  |  |  |  |  |  |  |
|  |  |  |  |  | 40 | 510100500-031-G |  | TRANS N,PMBT3904,40V,0.2A,G,SOT23-3,SMD | NXP SEMICONDUCTORS | PMBT3904 |  | G |  |  |  |  |  |  |  |
| Single | N |  | N | 41 | 41 | 610601801-32D-G |  | RES,0.5mOhm,+/-1%,2W,G,SMD1225 | Thin Film Technology Corporation | CPA1225R0M50FW-T5 | 1 | G | PHAR1 |  |  |  |  |  |  |
| Multi | ND |  | Y(5) | 42 | 42 | 61100DA00-017-G |  | RES,33KOhm,+/-0.1%,1/16W,G,SMD0402 | KOA SPEER ELECTRONICS, INC. | RN731ETTP3302B25 | 1 | G | PHAR2 |  |  |  |  |  |  |
|  |  |  |  |  | 42 | 61100DA00-011-G |  | RES,33KOhm,+/-0.1%,1/16W,G,SMD0402 | YAGEO CORPORATION COMPONENT | RT0402BRD0733KL |  | G |  |  |  |  |  |  |  |
|  |  |  |  |  | 42 | 61100DA00-012-G |  | RES,33KOhm,+/-0.1%,1/16W,G,SMD0402 | WALSIN TECHNOLOGY CORPORATION | WF04U3302BTL |  | G |  |  |  |  |  |  |  |
| Multi | N | Other | Y(4) | 43 | 43 | 610130Y00-017-G |  | RES,1 Ohm,+/-1%,1/3W,G,SMD1206 | KOA SPEER ELECTRONICS, INC. | SR732BTTD1R00F | 1 | G | PHAR4 |  |  |  |  |  |  |
|  |  |  |  |  | 43 | 610122P00-012-G |  | RES,1 Ohm,+/-1%,1/2W,G,SMD1206 | WALSIN TECHNOLOGY CORPORATION | WF12P1R00FTL |  | G |  |  |  |  |  |  |  |
|  |  |  |  |  | 43 | 610122P00-011-G |  | RES,1 Ohm,+/-1%,1/2W,G,SMD1206 | YAGEO CORPORATION COMPONENT | RC1206FR-7W1RL |  | G |  |  |  |  |  |  |  |
|  |  |  |  |  | 43 | 610122P00-044-G |  | RES,1 Ohm,+/-1%,1/2W,G,SMD1206 | TA-I TECHNOLOGY CO., LTD. | RMH12FT1R00 |  | G |  |  |  |  |  |  |  |
| Multi | ND |  | Y(5) | 44 | 44 | 61100QM00-017-G |  | RES,100KOhm,+/-0.1%,1/10W,G,SMD0603 | KOA SPEER ELECTRONICS, INC. | RN73H1JTTD1003B25 | 2 | G | PHAR5,PHAR7 |  |  |  |  |  |  |
|  |  |  |  |  | 44 | 61100QM00-012-G |  | RES,100KOhm,+/-0.1%,1/10W,G,SMD0603 | WALSIN TECHNOLOGY CORPORATION | WF06Q1003BTL |  | G |  |  |  |  |  |  |  |
|  |  |  |  |  | 44 | 61100QM00-011-G |  | RES,100KOhm,+/-0.1%,1/10W,G,SMD0603 | YAGEO CORPORATION COMPONENT | RT0603BRD07100KL |  | G |  |  |  |  |  |  |  |
| Multi | N | ND | Y(4) | 45 | 45 | 610100200-017-G | - | RES,7.5KOhm,+/-1%,1/10W,G,SMD0603 | KOA SPEER ELECTRONICS, INC. | RK73H1JTTD7501F | 1 | G | PHAR6 |  |  |  |  |  |  |
|  |  |  |  |  | 45 | 610100200-012-G |  | RES,7.5KOhm,+/-1%,1/10W,G,SMD0603 | WALSIN TECHNOLOGY CORPORATION | WR06X7501FTL |  | G |  |  |  |  |  |  |  |
|  |  |  |  |  | 45 | 610100200-011-G |  | RES,7.5KOhm,+/-1%,1/10W,G,SMD0603 | YAGEO CORPORATION COMPONENT | RC0603FR-077K5L |  | G |  |  |  |  |  |  |  |
|  |  |  |  |  | 45 | 610100200-044-G |  | RES,7.5KOhm,+/-1%,1/10W,G,SMD0603 | TA-I TECHNOLOGY CO., LTD. | RM06FTN7501 |  | G |  |  |  |  |  |  |  |
| Multi | N | other | Y(4) | 46 | 46 | 610103Y00-017-G |  | RES,10 Ohm,+/-1%,1/10W,G,SMD0603 | KOA SPEER ELECTRONICS, INC. | RK73H1JTTD10R0F | 3 | G | PHAR8,PHAR14,PHAR15 |  |  |  |  |  |  |
|  |  |  |  |  | 46 | 610103Y00-011-G |  | RES,10 Ohm,+/-1%,1/10W,G,SMD0603 | YAGEO CORPORATION COMPONENT | RC0603FR-0710RL |  | G |  |  |  |  |  |  |  |
|  |  |  |  |  | 46 | 610103Y00-044-G |  | RES,10 Ohm,+/-1%,1/10W,G,SMD0603 | TA-I TECHNOLOGY CO., LTD. | RM06FTN10R0 |  | G |  |  |  |  |  |  |  |
|  |  |  |  |  | 46 | 610103Y00-012-G |  | RES,10 Ohm,+/-1%,1/10W,G,SMD0603 | WALSIN TECHNOLOGY CORPORATION | WR06X10R0FTL |  | G |  |  |  |  |  |  |  |
|  |  |  |  |  | 46 | 610103Y00-024-G |  | RES,10 Ohm,+/-1%,1/10W,G,SMD0603 | PANASONIC INDUSTRIAL CO.,LTD. | ERJ3EKF10R0V |  | G |  |  |  |  |  |  |  |
| Multi | N | ND | Y(4) | 47 | 47 | 61010L300-017-G | - | RES,1KOhm,+/-1%,1/16W,G,SMD0402 | KOA SPEER ELECTRONICS, INC. | RK73H1ETTP1001F | 1 | G | PHAR9 |  |  |  |  |  |  |
|  |  |  |  |  | 47 | 61010L300-012-G |  | RES,1KOhm,+/-1%,1/16W,G,SMD0402 | WALSIN TECHNOLOGY CORPORATION | WR04X1001FTL |  | G |  |  |  |  |  |  |  |
|  |  |  |  |  | 47 | 61010L300-011-G |  | RES,1KOhm,+/-1%,1/16W,G,SMD0402 | YAGEO CORPORATION COMPONENT | RC0402FR-071KL |  | G |  |  |  |  |  |  |  |
|  |  |  |  |  | 47 | 61010L300-044-G |  | RES,1KOhm,+/-1%,1/16W,G,SMD0402 | TA-I TECHNOLOGY CO., LTD. | RM04FTN1001 |  | G |  |  |  |  |  |  |  |
|  |  |  |  |  | 47 | 61010L300-024-G |  | RES,1KOhm,+/-1%,1/16W,G,SMD0402 | PANASONIC INDUSTRIAL CO.,LTD. | ERJ2RKF1001X |  | G |  |  |  |  |  |  |  |
|  |  |  |  |  | 47 | 61010L300-029-G |  | RES,1KOhm,+/-1%,1/16W,G,SMD0402 | VISHAY ENTER TECHNO LOGY.INC | CRCW04021K00FKED |  | G |  |  |  |  |  |  |  |
| Multi | ND |  | Y(4) | 48 | 48 | 61013GW00-017-G |  | RES,150KOhm,+/-1%,1/8W,G,SMD0805 | KOA SPEER ELECTRONICS, INC. | RK73H2ATTD1503F | 1 | G | PHAR13 |  |  |  |  |  |  |
|  |  |  |  |  | 48 | 61013GW00-012-G |  | RES,150KOhm,+/-1%,1/8W,G,SMD0805 | WALSIN TECHNOLOGY CORPORATION | WR08X1503FTL |  | G |  |  |  |  |  |  |  |
|  |  |  |  |  | 48 | 61013GW00-011-G |  | RES,150KOhm,+/-1%,1/8W,G,SMD0805 | YAGEO CORPORATION COMPONENT | RC0805FR-07150KL |  | G |  |  |  |  |  |  |  |
|  |  |  |  |  | 48 | 61013GW00-044-G |  | RES,150KOhm,+/-1%,1/8W,G,SMD0805 | TA-I TECHNOLOGY CO., LTD. | RM10FTN1503 |  | G |  |  |  |  |  |  |  |
| Multi | N | ND | Y(4) | 49 | 49 | 610114F00-017-G | - | RES,3.16KOhm,+/-1%,1/16W,G,SMD0402 | KOA SPEER ELECTRONICS, INC. | RK73H1ETTP3161F | 1 | G | PHAR20 |  |  |  |  |  |  |
|  |  |  |  |  | 49 | 610114F00-012-G |  | RES,3.16KOhm,+/-1%,1/16W,G,SMD0402 | WALSIN TECHNOLOGY CORPORATION | WR04X3161FTL |  | G |  |  |  |  |  |  |  |
|  |  |  |  |  | 49 | 610114F00-011-G |  | RES,3.16KOhm,+/-1%,1/16W,G,SMD0402 | YAGEO CORPORATION COMPONENT | RC0402FR-073K16L |  | G |  |  |  |  |  |  |  |
|  |  |  |  |  | 49 | 610114F00-044-G |  | RES,3.16KOhm,+/-1%,1/16W,G,SMD0402 | TA-I TECHNOLOGY CO., LTD. | RM04FTN3161 |  | G |  |  |  |  |  |  |  |
| Multi | ND | ND | Y(4) | 50 | 50 | 61011NM00-017-G |  | RES,6.81KOhm,+/-1%,1/16W,G,SMD0402 | KOA SPEER ELECTRONICS, INC. | RK73H1ETTP6811F | 1 | G | PHAR22 |  |  |  |  |  |  |
|  |  |  |  |  | 50 | 61011NM00-012-G |  | RES,6.81KOhm,+/-1%,1/16W,G,SMD0402 | WALSIN TECHNOLOGY CORPORATION | WR04X6811FTL |  | G |  |  |  |  |  |  |  |
|  |  |  |  |  | 50 | 61011NM00-011-G |  | RES,6.81KOhm,+/-1%,1/16W,G,SMD0402 | YAGEO CORPORATION COMPONENT | RC0402FR-076K81L |  | G |  |  |  |  |  |  |  |
|  |  |  |  |  | 50 | 61011NM00-044-G |  | RES,6.81KOhm,+/-1%,1/16W,G,SMD0402 | TA-I TECHNOLOGY CO., LTD. | RM04FTN6811 |  | G |  |  |  |  |  |  |  |
| Multi | ND | ND | Y(4) | 51 | 51 | 61010LA00-017-G | - | RES,4.7KOhm,+/-1%,1/16W,G,SMD0402 | KOA SPEER ELECTRONICS, INC. | RK73H1ETTP4701F | 50 | G | R2,R3,R4,R12,R13,R14,R18,R19,R20,R21,R22,R25,R26,R27,R28,PHAR28,R29,PHAR29,PHAR30,R34,R35,R36,R39,R40,R41,R42,R43,R46,R47,R48,R49,R50,R54,R55,R114,R115,R126,R127,R141,R154,R156,R169,R170,R178,R179,R190,R191,R501,R1822,R1823 |  |  |  |  |  |  |
|  |  |  |  |  | 51 | 61010LA00-012-G |  | RES,4.7KOhm,+/-1%,1/16W,G,SMD0402 | WALSIN TECHNOLOGY CORPORATION | WR04X4701FTL |  | G |  |  |  |  |  |  |  |
|  |  |  |  |  | 51 | 61010LA00-011-G |  | RES,4.7KOhm,+/-1%,1/16W,G,SMD0402 | YAGEO CORPORATION COMPONENT | RC0402FR-074K7L |  | G |  |  |  |  |  |  |  |
|  |  |  |  |  | 51 | 61010LA00-044-G |  | RES,4.7KOhm,+/-1%,1/16W,G,SMD0402 | TA-I TECHNOLOGY CO., LTD. | RM04FTN4701 |  | G |  |  |  |  |  |  |  |
| Multi | ND | ND | Y(4) | 52 | 52 | 610113D00-017-G | - | RES,10.5KOhm,+/-1%,1/16W,G,SMD0402 | KOA SPEER ELECTRONICS, INC. | RK73H1ETTP1052F | 1 | G | PHAR35 |  |  |  |  |  |  |
|  |  |  |  |  | 52 | 610113D00-011-G |  | RES,10.5KOhm,+/-1%,1/16W,G,SMD0402 | YAGEO CORPORATION COMPONENT | RC0402FR-0710K5L |  | G |  |  |  |  |  |  |  |
|  |  |  |  |  | 52 | 610113D00-012-G |  | RES,10.5KOhm,+/-1%,1/16W,G,SMD0402 | WALSIN TECHNOLOGY CORPORATION | WR04X1052FTL |  | G |  |  |  |  |  |  |  |
|  |  |  |  |  | 52 | 610113D00-044-G |  | RES,10.5KOhm,+/-1%,1/16W,G,SMD0402 | TA-I TECHNOLOGY CO., LTD. | RM04FTN1052 |  | G |  |  |  |  |  |  |  |
| Multi |  | Resistor | Y(4) | 53 | 53 | 610107H00-017-G | PJ502 | RES,4.02KOhm,+/-1%,1/10W,G,SMD0603 | KOA SPEER ELECTRONICS, INC. | RK73H1JTTD4021F | 1 | G | PHAR44 |  |  |  |  |  |  |
|  |  |  |  |  | 53 | 610107H00-012-G |  | RES,4.02KOhm,+/-1%,1/10W,G,SMD0603 | WALSIN TECHNOLOGY CORPORATION | WR06X4021FTL |  | G |  |  |  |  |  |  |  |
|  |  |  |  |  | 53 | 610107H00-011-G |  | RES,4.02KOhm,+/-1%,1/10W,G,SMD0603 | YAGEO CORPORATION COMPONENT | RC0603FR-074K02L |  | G |  |  |  |  |  |  |  |
|  |  |  |  |  | 53 | 610107H00-044-G |  | RES,4.02KOhm,+/-1%,1/10W,G,SMD0603 | TA-I TECHNOLOGY CO., LTD. | RM06FTN4021 |  | G |  |  |  |  |  |  |  |
| Single | ND |  | Y(1) | 54 | 54 | 32023RR00-183-G |  | IC,Power Controller,LM5066IPMHX/NOPB,G,HTSSOP-28,SMD | TEXAS INSTRUMENTS | LM5066IPMHX/NOPB | 1 | G | PHAU1 |  |  |  |  |  |  |
| Multi | N |  | Y(3) | 55 | 55 | 62012GG00-015-G |  | CAP,10uF,+/-10%,X7S,25V,G,SMD0805 | MURATA ELEC. NORTH AMERICA | GRM21BC71E106K | 1 | G | PSRC3 |  |  |  |  |  |  |
|  |  |  |  |  | 55 | 62012GG00-012-G |  | CAP,10uF,+/-10%,X7S,25V,G,SMD0805 | WALSIN TECHNOLOGY CORPORATION | 0805A106K250CT |  | G |  |  |  |  |  |  |  |
| Multi | N |  | Y(1) | 56 | 56 | 62012T300-015-G |  | CAP,1uF,+/-10%,X7S,25V,G,SMD0402 | MURATA ELEC. NORTH AMERICA | GRM155C71E105KE11D | 1 | G | PSRC4 |  |  |  |  |  |  |
|  |  |  |  |  | 56 | 620138700-026-G |  | CAP,1uF,+/-10%,X6S,25V,G,SMD0402 | SAMSUNG SEMICONDUCTOR | CL05X105KA5NQNC |  | G |  |  |  |  |  |  |  |
|  |  |  |  |  | 56 | 620138700-015-G |  | CAP,1uF,+/-10%,X6S,25V,G,SMD0402 | MURATA | GRM155C81E105KE11D |  | G |  |  |  |  |  |  |  |
| Multi | ND |  | Y(3) | 57 | 57 | 62012P100-015-G |  | CAP,2.2uF,+/-20%,X7S,10V,G,SMD0402 | MURATA ELEC. NORTH AMERICA | GRM155C71A225M | 1 | G | PSRC5 |  |  |  |  |  |  |
|  |  |  |  |  | 57 | 62012P100-012-G |  | CAP,2.2uF,+/-20%,X7S,10V,G,SMD0402 | WALSIN TECHNOLOGY CORPORATION | 0402A225M100CT |  | G |  |  |  |  |  |  |  |
| Multi | N |  | Y(1) | 58 | 58 | 62012PT00-015-G |  | CAP,22uF,+/-20%,X6S,16V,G,SMD0805 | MURATA ELEC. NORTH AMERICA | GRM21BC81C226M | 5 | G | PSRC7,PSRC8,PSRC11,PSRC12,PSRC15 |  |  |  |  |  |  |
|  |  |  |  |  | 58 | 62012PT00-023-G |  | CAP,22uF,+/-20%,X6S,16V,G,SMD0805 | TAIYO ELECTRIC IND.CO.LTD | EDK212BC6226MG-T |  | G |  |  |  |  |  |  |  |
| Multi | Y | 2 | Y(3) | 59 | 59 | 620105U00-015-G | - | CAP,220pF,+/-10%,X7R,50V,G,SMD0402 | MURATA ELEC. NORTH AMERICA | GRM155R71H221K | 1 | G | PSRC14 |  |  |  |  |  |  |
|  |  |  |  |  | 59 | 620105U00-012-G |  | CAP,220pF,+/-10%,X7R,50V,G,SMD0402 | WALSIN TECHNOLOGY CORPORATION | 0402B221K500CT |  | G |  |  |  |  |  |  |  |
|  |  |  |  |  | 59 | 620105U00-026-G |  | CAP,220pF,+/-10%,X7R,50V,G,SMD0402 | SAMSUNG SEMICONDUCTOR | CL05B221KB5NNNC |  | G |  |  |  |  |  |  |  |
| Multi | N |  | Y(3) | 60 | 60 | 62012H100-015-G |  | CAP,10uF,+/-20%,X6S,10V,G,SMD0603 | MURATA ELEC. NORTH AMERICA | GRM188C81A106M | 1 | G | PSRC16 |  |  |  |  |  |  |
|  |  |  |  |  | 60 | 62012H100-023-G |  | CAP,10uF,+/-20%,X6S,10V,G,SMD0603 | TAIYO ELECTRIC IND.CO.LTD | LMK107BC6106MA-T |  | G |  |  |  |  |  |  |  |
|  |  |  |  |  | 60 | 62012H100-026-G |  | CAP,10uF,+/-20%,X6S,10V,G,SMD0603 | SAMSUNG SEMICONDUCTOR | CL10X106MP8NRNC |  | G |  |  |  |  |  |  |  |
| Multi | N |  | Y(2) | 61 | 61 | 72010RE00-015-G |  | FB,26 Ohm@100MHz,+/-25%,6A,7mOhm,G,SMD0603 | MURATA ELEC. NORTH AMERICA | BLM18KG260TN1D | 1 | G | PSRL1 |  |  |  |  |  |  |
|  |  |  |  |  | 61 | 72010SJ00-059-G |  | FB,26 Ohm@100MHz,+/-25%,6A,10mOhm,G,SMD0603 | TAI-TECH ADVANCED ELECTRONICS CO., LTD. | HCB1608KF-260T60 |  | G |  |  |  |  |  |  |  |
| Multi | N |  | N | 62 | 62 | 63032PP00-088-G |  | IND,4.7uH@100KHz,+/-20%,5.5A,40mOhm,SHLD,G,SMD | COOPER BUSSMANN, INC. | HCM0703-4R7-R | 1 | G | PSRL2 |  |  |  |  |  |  |
|  |  |  |  |  | 62 | 63030PW00-034-G |  | Coil Ind,Shielded(SHLD),4.7uH@100KHz,+/-20%,5.5A,40mOhm,SMD,7.3*6.6*3.0,G | CYNTEC CO. LTD | PCMC063T-4R7MN |  | G |  |  |  |  |  |  |  |
|  |  |  |  |  | 62 | 63031AD04-129-G |  | IND,4.7uH@100KHz,+/-20%,5.5A,40mOhm,SHLD,G,SMD | MAG.LAYERS, SCIENTIFIC-TECHNICS (KUNSHAN) CO., LTD. | SPS-06CZ-4R7M-V1 |  | G |  |  |  |  |  |  |  |
| Multi | ND | ND | Y(4) | 63 | 63 | 61011R400-017-G |  | RES,34.8KOhm,+/-1%,1/16W,G,SMD0402 | KOA SPEER ELECTRONICS, INC. | RK73H1ETTP3482F | 1 | G | PSRR1 |  |  |  |  |  |  |
|  |  |  |  |  | 63 | 61011R400-012-G |  | RES,34.8KOhm,+/-1%,1/16W,G,SMD0402 | WALSIN TECHNOLOGY CORPORATION | WR04X3482FTL |  | G |  |  |  |  |  |  |  |
|  |  |  |  |  | 63 | 61011R400-011-G |  | RES,34.8KOhm,+/-1%,1/16W,G,SMD0402 | YAGEO CORPORATION COMPONENT | RC0402FR-0734K8L |  | G |  |  |  |  |  |  |  |
|  |  |  |  |  | 63 | 61011R400-044-G |  | RES,34.8KOhm,+/-1%,1/16W,G,SMD0402 | TA-I TECHNOLOGY CO., LTD. | RM04FTN3482 |  | G |  |  |  |  |  |  |  |
| Multi | ND | ND | Y(4) | 64 | 64 | 610114S00-017-G | - | RES,4.99KOhm,+/-1%,1/16W,G,SMD0402 | KOA SPEER ELECTRONICS, INC. | RK73H1ETTP4991F | 1 | G | PSRR3 |  |  |  |  |  |  |
|  |  |  |  |  | 64 | 610114S00-012-G |  | RES,4.99KOhm,+/-1%,1/16W,G,SMD0402 | WALSIN TECHNOLOGY CORPORATION | WR04X4991FTL |  | G |  |  |  |  |  |  |  |
|  |  |  |  |  | 64 | 610114S00-011-G |  | RES,4.99KOhm,+/-1%,1/16W,G,SMD0402 | YAGEO CORPORATION COMPONENT | RC0402FR-074K99L |  | G |  |  |  |  |  |  |  |
|  |  |  |  |  | 64 | 610114S00-044-G |  | RES,4.99KOhm,+/-1%,1/16W,G,SMD0402 | TA-I TECHNOLOGY CO., LTD. | RM04FTN4991 |  | G |  |  |  |  |  |  |  |
|  |  |  |  |  | 64 | 610114S00-024-G |  | RES,4.99KOhm,+/-1%,1/16W,G,SMD0402 | PANASONIC INDUSTRIAL CO.,LTD. | ERJ2RKF4991X |  | G |  |  |  |  |  |  |  |
| Multi | ND | ND | Y(4) | 65 | 65 | 61011HA00-017-G |  | RES,1 Ohm,+/-1%,1/16W,G,SMD0402 | KOA SPEER ELECTRONICS, INC. | RK73H1ETTP1R00F | 1 | G | PSRR5 |  |  |  |  |  |  |
|  |  |  |  |  | 65 | 61011HA00-012-G |  | RES,1 Ohm,+/-1%,1/16W,G,SMD0402 | WALSIN TECHNOLOGY CORPORATION | WR04W1R00FTL |  | G |  |  |  |  |  |  |  |
|  |  |  |  |  | 65 | 61011HA00-011-G |  | RES,1 Ohm,+/-1%,1/16W,G,SMD0402 | YAGEO CORPORATION COMPONENT | RC0402FR-071RL |  | G |  |  |  |  |  |  |  |
|  |  |  |  |  | 65 | 61011HA00-044-G |  | RES,1 Ohm,+/-1%,1/16W,G,SMD0402 | TA-I TECHNOLOGY CO., LTD. | RM04FTN1R00 |  | G |  |  |  |  |  |  |  |
|  |  |  |  |  | 65 | 61011HA00-029-G |  | RES,1 Ohm,+/-1%,1/16W,G,SMD0402 | VISHAY ENTER TECHNO LOGY.INC | CRCW04021R00FNED |  | G |  |  |  |  |  |  |  |
| Multi | N |  | Y(5) | 66 | 66 | 611004M00-017-G |  | RES,16.5KOhm,+/-0.1%,1/16W,G,SMD0402 | KOA SPEER ELECTRONICS, INC. | RN731ETTP1652B25 | 1 | G | PSRR17 |  |  |  |  |  |  |
|  |  |  |  |  | 66 | 611004M00-024-G |  | RES,16.5KOhm,+/-0.1%,1/16W,G,SMD0402 | PANASONIC INDUSTRIAL CO.,LTD. | ERA2AEB1652X |  | G |  |  |  |  |  |  |  |
| Multi | N |  | Y(5) | 67 | 67 | 61100YB00-017-G |  | RES,2.94KOhm,+/-0.1%,1/16W,G,SMD0402 | KOA SPEER ELECTRONICS, INC. | RN731ETTP2941B25 | 1 | G | PSRR19 |  |  |  |  |  |  |
|  |  |  |  |  | 67 | 61100YB00-011-G |  | RES,2.94KOhm,+/-0.1%,1/16W,G,SMD0402 | YAGEO CORPORATION COMPONENT | RT0402BRD072K94L |  |  |  |  |  |  |  |  |  |
|  |  |  |  |  | 67 | 61100YB00-044-G |  | RES,2.94KOhm,+/-0.1%,1/16W,G,SMD0402 | TA-I TECHNOLOGY CO., LTD | RB04BTP2941 |  |  |  |  |  |  |  |  |  |
| Single | ND |  | N | 68 | 68 | 32013PD00-238-G |  | IC,Regulator,IR3883MTRPbF,ADJ,3A,G,QFN-16,SMD | INTERNATIONAL RECTIFIER | IR3883MTRPBF | 1 | G | PSRU1 |  |  |  |  |  |  |
| Multi | ND | ND | N | 69 | 69 | 510301N00-223-G |  | MOS N,2N7002LT1G,60V,0.115A,7.5ohm@5V,G,SOT23-3,SMD | ON SEMICONDUCTOR CORP | 2N7002LT1G | 1 | G | PSUQ1 |  |  |  |  |  |  |
|  |  |  |  |  | 69 | 51030CQ00-185-G |  | MOS N,2N7002,60V,115mA,7.5ohm@5V,G,SOT23-3,SMD | FAIRCHILD SEMICONDUCTOR CORP | 2N7002 |  | G |  |  |  |  |  |  |  |
| Multi | ND | ND | Y(4) | 70 | 70 | 61011GD00-017-G | - | RES,15.4KOhm,+/-1%,1/16W,G,SMD0402 | KOA SPEER ELECTRONICS, INC. | RK73H1ETTP1542F | 1 | G | PSUR1 |  |  |  |  |  |  |
|  |  |  |  |  | 70 | 61011GD00-011-G |  | RES,15.4KOhm,+/-1%,1/16W,G,SMD0402 | YAGEO CORPORATION COMPONENT | RC0402FR-0715K4L |  | G |  |  |  |  |  |  |  |
|  |  |  |  |  | 70 | 61011GD00-012-G |  | RES,15.4KOhm,+/-1%,1/16W,G,SMD0402 | WALSIN TECHNOLOGY CORPORATION | WR04X1542FTL |  | G |  |  |  |  |  |  |  |
|  |  |  |  |  | 70 | 61011GD00-044-G |  | RES,15.4KOhm,+/-1%,1/16W,G,SMD0402 | TA-I TECHNOLOGY CO., LTD. | RM04FTN1542 |  | G |  |  |  |  |  |  |  |
| Multi | ND | ND | N | 71 | 71 | 510503B00-223-G |  | MOS N/N,NTZD3154NT1G,20V,0.54A,550m24.5V,G,SOT563-6,SMD | ON SEMICONDUCTOR CORP | NTZD3154NT1G | 1 | G | QN4 |  |  |  |  |  |  |
|  |  |  |  |  | 71 | 51050L500-029-G |  | MOS,N/N,Si1034CX-T1-GE3,20V,0.61A,G,SC-89-6,SMD | VISHAY ENTER TECHNO LOGY.INC | Si1034CX-T1-GE3 |  | G |  |  |  |  |  |  |  |
|  |  |  |  |  | 71 | 51050KW00-131-G |  | MOS N/N,SSM6N36FE,20V,500mA,0.63@5V,G,ES6-6,SMD | TOSHIBA ELECTRONICS ASIA LTD | SSM6N36FE |  | G |  |  |  |  |  |  |  |
| Multi | ND | ND | N | 72 | 72 | 510302R00-185-G |  | MOS N,BSS138,50V,0.22A,6ohm@4.5V,G,SOT23-3,SMD | FAIRCHILD SEMICONDUCTOR CORP | BSS138 | 12 | G | Q1,Q2,Q3,Q4,Q5,Q6,Q7,Q8,Q9,Q10,Q11,Q12 |  |  |  |  |  |  |
|  |  |  |  |  | 72 | 510309C00-237-G |  | MOS N,BSS138-7-F,50V,0.2A,3.5ohm@10V,G,SOT23-3,SMD | DIODES INCORPORATION | BSS138-7-F |  | G |  |  |  |  |  |  |  |
|  |  |  |  |  | 72 | 510301D00-223-G |  | MOS N,BSS138LT1G,50V,0.2A,3.5ohm@5V,G,SOT23-3,SMD | ON SEMICONDUCTOR CORP | BSS138LT1G |  | G |  |  |  |  |  |  |  |
| Single | Y |  | N | 73 | 73 | 51040EK00-185-G |  | MOS P,FDMS6681Z,30V,49A,5m@4.5V,G,Power56-8,SMD | FAIRCHILD SEMICONDUCTOR CORP | FDMS6681Z | 2 | G | Q13,Q14 |  |  |  |  |  |  |
| Multi | ND | ND | Y(4) | 74 | 74 | 61010H800-017-G |  | RES,5.11 Ohm,+/-1%,1/10W,G,SMD0603 | KOA SPEER ELECTRONICS, INC. | RK73H1JTTD5R11F | 2 | G | R11,R32 |  |  |  |  |  |  |
|  |  |  |  |  | 74 | 61010H800-012-G |  | RES,5.11 Ohm,+/-1%,1/10W,G,SMD0603 | WALSIN TECHNOLOGY CORPORATION | WR06W5R11FTL |  | G |  |  |  |  |  |  |  |
|  |  |  |  |  | 74 | 61010H800-011-G |  | RES,5.11 Ohm,+/-1%,1/10W,G,SMD0603 | YAGEO CORPORATION COMPONENT | RC0603FR-075R11L |  | G |  |  |  |  |  |  |  |
|  |  |  |  |  | 74 | 61010H800-044-G |  | RES,5.11 Ohm,+/-1%,1/10W,G,SMD0603 | TA-I TECHNOLOGY CO., LTD. | RM06FTN5R11 |  | G |  |  |  |  |  |  |  |
| Multi | N | Other | Y(4) | 75 | 75 | 61011MQ00-017-G | - | RES,4.75KOhm,+/-1%,1/16W,G,SMD0402 | KOA SPEER ELECTRONICS, INC. | RK73H1ETTP4751F | 4 | G | R15,R33,R1772,R1814 |  |  |  |  |  |  |
|  |  |  |  |  | 75 | 61011MQ00-012-G |  | RES,4.75KOhm,+/-1%,1/16W,G,SMD0402 | WALSIN TECHNOLOGY CORPORATION | WR04X4751FTL |  | G |  |  |  |  |  |  |  |
|  |  |  |  |  | 75 | 61011MQ00-011-G |  | RES,4.75KOhm,+/-1%,1/16W,G,SMD0402 | YAGEO CORPORATION COMPONENT | RC0402FR-074K75L |  | G |  |  |  |  |  |  |  |
|  |  |  |  |  | 75 | 61011MQ00-044-G |  | RES,4.75KOhm,+/-1%,1/16W,G,SMD0402 | TA-I TECHNOLOGY CO., LTD. | RM04FTN4751 |  | G |  |  |  |  |  |  |  |
| Multi | N | ND | Y(4) | 76 | 76 | 610115J00-017-G | - | RES,33 Ohm,+/-1%,1/16W,G,SMD0402 | KOA SPEER ELECTRONICS, INC. | RK73H1ETTP33R0F | 2 | G | R17,R37 |  |  |  |  |  |  |
|  |  |  |  |  | 76 | 610115J00-012-G |  | RES,33 Ohm,+/-1%,1/16W,G,SMD0402 | WALSIN TECHNOLOGY CORPORATION | WR04X33R0FTL |  | G |  |  |  |  |  |  |  |
|  |  |  |  |  | 76 | 610115J00-011-G |  | RES,33 Ohm,+/-1%,1/16W,G,SMD0402 | YAGEO CORPORATION COMPONENT | RC0402FR-0733RL |  | G |  |  |  |  |  |  |  |
|  |  |  |  |  | 76 | 610115J00-044-G |  | RES,33 Ohm,+/-1%,1/16W,G,SMD0402 | TA-I TECHNOLOGY CO., LTD. | RM04FTN33R0 |  | G |  |  |  |  |  |  |  |
|  |  |  |  |  | 76 | 610115J00-024-G |  | RES,33 Ohm,+/-1%,1/16W,G,SMD0402 | PANASONIC INDUSTRIAL CO.,LTD. | ERJ2RKF33R0X |  | G |  |  |  |  |  |  |  |
| Multi | ND | ND | Y(4) | 77 | 77 | 61010L100-017-G | - | RES,100KOhm,+/-1%,1/16W,G,SMD0402 | KOA SPEER ELECTRONICS, INC. | RK73H1ETTP1003F | 3 | G | R45,R233,R236 |  |  |  |  |  |  |
|  |  |  |  |  | 77 | 61010L100-012-G |  | RES,100KOhm,+/-1%,1/16W,G,SMD0402 | WALSIN TECHNOLOGY CORPORATION | WR04X1003FTL |  | G |  |  |  |  |  |  |  |
|  |  |  |  |  | 77 | 61010L100-011-G |  | RES,100KOhm,+/-1%,1/16W,G,SMD0402 | YAGEO CORPORATION COMPONENT | RC0402FR-07100KL |  | G |  |  |  |  |  |  |  |
|  |  |  |  |  | 77 | 61010L100-044-G |  | RES,100KOhm,+/-1%,1/16W,G,SMD0402 | TA-I TECHNOLOGY CO., LTD. | RM04FTN1003 |  | G |  |  |  |  |  |  |  |
|  |  |  |  |  | 77 | 61010L106-029-G |  | RES,100KOhm,+/-1%,1/16W,G,SMD0402 | VISHAY ENTER TECHNO LOGY.INC | CRCW0402100KFKEDC |  | G |  |  |  |  |  |  |  |
|  |  |  |  |  | 77 | 61010L100-024-G |  | RES,100KOhm,+/-1%,1/16W,G,SMD0402 | PANASONIC INDUSTRIAL CO.,LTD. | ERJ2RKF1003X |  | G |  |  |  |  |  |  |  |
| Multi | N | ND | Y(4) | 78 | 78 | 61011DR00-017-G |  | RES,2.2KOhm,+/-1%,1/16W,G,SMD0402 | KOA SPEER ELECTRONICS, INC. | RK73H1ETTP2201F | 24 | G | R59,R61,R73,R75,R87,R89,R116,R117,R118,R128,R129,R130,R155,R157,R158,R166,R167,R168,R180,R181,R182,R192,R193,R194 |  |  |  |  |  |  |
|  |  |  |  |  | 78 | 61011DR00-012-G |  | RES,2.2KOhm,+/-1%,1/16W,G,SMD0402 | WALSIN TECHNOLOGY CORPORATION | WR04X2201FTL |  | G |  |  |  |  |  |  |  |
|  |  |  |  |  | 78 | 61011DR00-011-G |  | RES,2.2KOhm,+/-1%,1/16W,G,SMD0402 | YAGEO CORPORATION COMPONENT | RC0402FR-072K2L |  | G |  |  |  |  |  |  |  |
|  |  |  |  |  | 78 | 61011DR00-044-G |  | RES,2.2KOhm,+/-1%,1/16W,G,SMD0402 | TA-I TECHNOLOGY CO., LTD. | RM04FTN2201 |  | G |  |  |  |  |  |  |  |
|  |  |  |  |  | 78 | 61011DR00-029-G |  | RES,2.2KOhm,+/-1%,1/16W,G,SMD0402 | VISHAY ENTER TECHNO LOGY.INC | CRCW04022K20FKED |  | G |  |  |  |  |  |  |  |
| Multi | N | Other | Y(4) | 79 | 79 | 61011DG01-017-G |  | RES,10KOhm,+/-1%,1/20W,G,SMD0201 | KOA SPEER ELECTRONICS, INC. | RK73H1HTTC1002F | 6 | G | R98,R99,R106,R107,R110,R112 |  |  |  |  |  |  |
|  |  |  |  |  | 79 | 61011DG00-012-G |  | RES,10KOhm,+/-1%,1/20W,G,SMD0201 | WALSIN TECHNOLOGY CORPORATION | WR02X1002FAL |  | G |  |  |  |  |  |  |  |
|  |  |  |  |  | 79 | 61011DG00-011-G |  | RES,10KOhm,+/-1%,1/20W,G,SMD0201 | YAGEO CORPORATION COMPONENT | RC0201FR-0710KL |  | G |  |  |  |  |  |  |  |
|  |  |  |  |  | 79 | 61011DG00-044-G |  | RES,10KOhm,+/-1%,1/20W,G,SMD0201 | TA-I TECHNOLOGY CO., LTD. | RM02FTN1002 |  | G |  |  |  |  |  |  |  |
| Multi | N | Other | Y(4) | 80 | 80 | 61011DL01-017-G | - | RES,1KOhm,+/-1%,1/20W,G,SMD0201 | KOA SPEER ELECTRONICS, INC. | RK73H1HTTC1001F | 2 | G | R100,R102 |  |  |  |  |  |  |
|  |  |  |  |  | 80 | 61011DL00-012-G |  | RES,1KOhm,+/-1%,1/20W,G,SMD0201 | WALSIN TECHNOLOGY CORPORATION | WR02X1001FAL |  | G |  |  |  |  |  |  |  |
|  |  |  |  |  | 80 | 61011DL00-011-G |  | RES,1KOhm,+/-1%,1/20W,G,SMD0201 | YAGEO CORPORATION COMPONENT | RC0201FR-071KL |  | G |  |  |  |  |  |  |  |
|  |  |  |  |  | 80 | 61011DL00-044-G |  | RES,1KOhm,+/-1%,1/20W,G,SMD0201 | TA-I TECHNOLOGY CO., LTD. | RM02FTN1001 |  | G |  |  |  |  |  |  |  |
| Multi | N | ND | Y(4) | 81 | 81 | 61010AN00-017-G |  | RES,1MOhm,+/-5%,1/16W,G,SMD0402 | KOA SPEER ELECTRONICS, INC. | RK73B1ETTP105J | 2 | G | R101,R103 |  |  |  |  |  |  |
|  |  |  |  |  | 81 | 61010AN00-012-G |  | RES,1MOhm,+/-5%,1/16W,G,SMD0402 | WALSIN TECHNOLOGY CORPORATION | WR04X105JTL |  | G |  |  |  |  |  |  |  |
|  |  |  |  |  | 81 | 61010AN00-011-G |  | RES,1MOhm,+/-5%,1/16W,G,SMD0402 | YAGEO CORPORATION COMPONENT | RC0402JR-071ML |  | G |  |  |  |  |  |  |  |
|  |  |  |  |  | 81 | 61010AN00-044-G |  | RES,1MOhm,+/-5%,1/16W,G,SMD0402 | TA-I TECHNOLOGY CO., LTD. | RM04JTN105 |  | G |  |  |  |  |  |  |  |
| Multi | N | Other | Y(4) | 82 | 82 | 610132800-017-G |  | RES,1.54KOhm,+/-1%,1/20W,G,SMD0201 | KOA SPEER ELECTRONICS, INC. | RK73H1HTTC1541F | 2 | G | R104,R105 |  |  |  |  |  |  |
|  |  |  |  |  | 82 | 610132800-012-G |  | RES,1.54KOhm,+/-1%,1/20W,G,SMD0201 | WALSIN TECHNOLOGY CORPORATION | WR02X1541FAL |  | G |  |  |  |  |  |  |  |
|  |  |  |  |  | 82 | 610132800-044-G |  | RES,1.54KOhm,+/-1%,1/20W,G,SMD0201 | TA-I TECHNOLOGY CO., LTD. | RM02FTN1541 |  | G |  |  |  |  |  |  |  |
| Multi | ND | ND | Y(4) | 83 | 83 | 610113T00-017-G | - | RES,13.7KOhm,+/-1%,1/16W,G,SMD0402 | KOA SPEER ELECTRONICS, INC. | RK73H1ETTP1372F | 2 | G | R108,R109 |  |  |  |  |  |  |
|  |  |  |  |  | 83 | 610113T00-012-G |  | RES,13.7KOhm,+/-1%,1/16W,G,SMD0402 | WALSIN TECHNOLOGY CORPORATION | WR04X1372FTL |  | G |  |  |  |  |  |  |  |
|  |  |  |  |  | 83 | 610113T00-011-G |  | RES,13.7KOhm,+/-1%,1/16W,G,SMD0402 | YAGEO CORPORATION COMPONENT | RC0402FR-0713K7L |  | G |  |  |  |  |  |  |  |
|  |  |  |  |  | 83 | 610113T00-044-G |  | RES,13.7KOhm,+/-1%,1/16W,G,SMD0402 | TA-I TECHNOLOGY CO., LTD. | RM04FTN1372 |  | G |  |  |  |  |  |  |  |
| Multi | N | ND | Y(4) | 84 | 84 | 61011KY00-017-G |  | RES,3.83KOhm,+/-1%,1/16W,G,SMD0402 | KOA SPEER ELECTRONICS, INC. | RK73H1ETTP3831F | 2 | G | R111,R113 |  |  |  |  |  |  |
|  |  |  |  |  | 84 | 61011KY00-012-G |  | RES,3.83KOhm,+/-1%,1/16W,G,SMD0402 | WALSIN TECHNOLOGY CORPORATION | WR04X3831FTL |  | G |  |  |  |  |  |  |  |
|  |  |  |  |  | 84 | 61011KY00-011-G |  | RES,3.83KOhm,+/-1%,1/16W,G,SMD0402 | YAGEO CORPORATION COMPONENT | RC0402FR-073K83L |  | G |  |  |  |  |  |  |  |
|  |  |  |  |  | 84 | 61011KY00-044-G |  | RES,3.83KOhm,+/-1%,1/16W,G,SMD0402 | TA-I TECHNOLOGY CO., LTD. | RM04FTN3831 |  | G |  |  |  |  |  |  |  |
|  |  |  |  |  | 84 | 61011KY00-029-G |  | RES,3.83KOhm,+/-1%,1/16W,G,SMD0402 | VISHAY ENTER TECHNO LOGY.INC | CRCW04023K83FKED |  | G |  |  |  |  |  |  |  |
| Multi | N |  | Y(5) | 85 | 85 | 61100LR00-017-G |  | RES,100 Ohm,+/-1%,1/16W,G,SMD0402 | KOA SPEER ELECTRONICS, INC. | RN731ETTP1000F50 | 15 | G | R120,R122,R132,R134,R160,R163,R173,R175,R184,R186,R196,R198,R500,R1484,R1779 |  |  |  |  |  |  |
|  |  |  |  |  | 85 | 61100LR01-011-G |  | RES,100 Ohm,+/-1%,1/16W,G,SMD0402 | YAGEO CORPORATION COMPONENT | RT0402FRE07100RL |  | G |  |  |  |  |  |  |  |
|  |  |  |  |  | 85 | 61100LR00-044-G |  | RES,100 Ohm,+/-1%,1/16W,G,SMD0402 | TA-I TECHNOLOGY CO., LTD. | RB04FTS1000 |  | G |  |  |  |  |  |  |  |
|  |  |  |  |  | 85 | 61100LR00-012-G |  | RES,100 Ohm,+/-1%,1/16W,G,SMD0402 | WALSIN TECHNOLOGY CORPORATION | WF04T1000FTL |  | G |  |  |  |  |  |  |  |
| Multi | ND | ND | Y(4) | 86 | 86 | 61011CY00-017-G |  | RES,5.6KOhm,+/-1%,1/16W,G,SMD0402 | KOA SPEER ELECTRONICS, INC. | RK73H1ETTP5601F | 12 | G | R124,R125,R136,R137,R164,R165,R176,R177,R188,R189,R200,R201 |  |  |  |  |  |  |
|  |  |  |  |  | 86 | 61011CY00-012-G |  | RES,5.6KOhm,+/-1%,1/16W,G,SMD0402 | WALSIN TECHNOLOGY CORPORATION | WR04X5601FTL |  | G |  |  |  |  |  |  |  |
|  |  |  |  |  | 86 | 61011CY00-011-G |  | RES,5.6KOhm,+/-1%,1/16W,G,SMD0402 | YAGEO CORPORATION COMPONENT | RC0402FR-075K6L |  | G |  |  |  |  |  |  |  |
|  |  |  |  |  | 86 | 61011CY00-044-G |  | RES,5.6KOhm,+/-1%,1/16W,G,SMD0402 | TA-I TECHNOLOGY CO., LTD. | RM04FTN5601 |  | G |  |  |  |  |  |  |  |
|  |  |  |  |  | 86 | 61011CY00-029-G |  | RES,5.6KOhm,+/-1%,1/16W,G,SMD0402 | VISHAY ENTER TECHNO LOGY.INC | CRCW04025K60FKED |  | G |  |  |  |  |  |  |  |
| Multi | ND | ND | Y(4) | 87 | 87 | 61011QD00-017-G | - | RES,330 Ohm,+/-1%,1/16W,G,SMD0402 | KOA SPEER ELECTRONICS, INC. | RK73H1ETTP3300F | 12 | G | R142,R143,R144,R145,R146,R147,R148,R149,R150,R151,R152,R153 |  |  |  |  |  |  |
|  |  |  |  |  | 87 | 61011QD00-012-G |  | RES,330 Ohm,+/-1%,1/16W,G,SMD0402 | WALSIN TECHNOLOGY CORPORATION | WR04X3300FTL |  | G |  |  |  |  |  |  |  |
|  |  |  |  |  | 87 | 61011QD00-011-G |  | RES,330 Ohm,+/-1%,1/16W,G,SMD0402 | YAGEO CORPORATION COMPONENT | RC0402FR-07330RL |  | G |  |  |  |  |  |  |  |
|  |  |  |  |  | 87 | 61011QD00-044-G |  | RES,330 Ohm,+/-1%,1/16W,G,SMD0402 | TA-I TECHNOLOGY CO., LTD. | RM04FTN3300 |  | G |  |  |  |  |  |  |  |
| Multi | ND | ND | Y(4) | 88 | 88 | 61011H500-017-G | - | RES,22 Ohm,+/-1%,1/16W,G,SMD0402 | KOA SPEER ELECTRONICS, INC. | RK73H1ETTP22R0F | 1 | G | R202 |  |  |  |  |  |  |
|  |  |  |  |  | 88 | 61011H500-012-G |  | RES,22 Ohm,+/-1%,1/16W,G,SMD0402 | WALSIN TECHNOLOGY CORPORATION | WR04X22R0FTL |  | G |  |  |  |  |  |  |  |
|  |  |  |  |  | 88 | 61011H500-011-G |  | RES,22 Ohm,+/-1%,1/16W,G,SMD0402 | YAGEO CORPORATION COMPONENT | RC0402FR-0722RL |  | G |  |  |  |  |  |  |  |
|  |  |  |  |  | 88 | 61011H500-044-G |  | RES,22 Ohm,+/-1%,1/16W,G,SMD0402 | TA-I TECHNOLOGY CO., LTD. | RM04FTN22R0 |  | G |  |  |  |  |  |  |  |
|  |  |  |  |  | 88 | 61011H500-024-G |  | RES,22 Ohm,+/-1%,1/16W,G,SMD0402 | PANASONIC INDUSTRIAL CO.,LTD. | ERJ2RKF22R0X |  | G |  |  |  |  |  |  |  |
| Multi | N | Other | Y(4) | 89 | 89 | 61010JY00-017-G | - | RES,220 Ohm,+/-5%,1/16W,G,SMD0402 | KOA SPEER ELECTRONICS, INC. | RK73B1ETTP221J | 3 | G | R203,R1770,R1771 |  |  |  |  |  |  |
|  |  |  |  |  | 89 | 61010JY00-012-G |  | RES,220 Ohm,+/-5%,1/16W,G,SMD0402 | WALSIN TECHNOLOGY CORPORATION | WR04X221JTL |  | G |  |  |  |  |  |  |  |
|  |  |  |  |  | 89 | 61010JY00-011-G |  | RES,220 Ohm,+/-5%,1/16W,G,SMD0402 | YAGEO CORPORATION COMPONENT | RC0402JR-07220RL |  | G |  |  |  |  |  |  |  |
|  |  |  |  |  | 89 | 61010JY00-044-G |  | RES,220 Ohm,+/-5%,1/16W,G,SMD0402 | TA-I TECHNOLOGY CO., LTD. | RM04JTN221 |  | G |  |  |  |  |  |  |  |
| Multi | ND | ND | Y(4) | 90 | 90 | 61012LR00-017-G |  | RES,1KOhm,+/-0.5%,1/16W,G,SMD0402 | KOA SPEER ELECTRONICS, INC. | RK73H1ETTP1001D | 1 | G | R1480 |  |  |  |  |  |  |
|  |  |  |  |  | 90 | 61012LR00-012-G |  | RES,1KOhm,+/-0.5%,1/16W,G,SMD0402 | WALSIN TECHNOLOGY CORPORATION | WF04H1001DTL |  | G |  |  |  |  |  |  |  |
|  |  |  |  |  | 90 | 61012LR00-011-G |  | RES,1KOhm,+/-0.5%,1/16W,G,SMD0402 | YAGEO CORPORATION COMPONENT | RC0402DR-071KL |  | G |  |  |  |  |  |  |  |
|  |  |  |  |  | 90 | 61012LR00-044-G |  | RES,1KOhm,+/-0.5%,1/16W,G,SMD0402 | TA-I TECHNOLOGY CO., LTD. | RM04DTN1001 |  | G |  |  |  |  |  |  |  |
| Multi | ND | ND | N | 91 | 91 | 61100QT01-017-G | - | RES,10 Ohm,+/-0.5%,1/16W,G,SMD0402 | KOA SPEER ELECTRONICS, INC. | RN731ETTP10R0D25 | 1 | G | R1483 |  |  |  |  |  |  |
|  |  |  |  |  | 91 | 61100QT00-011-G |  | RES,10 Ohm,+/-0.5%,1/16W,G,SMD0402 | YAGEO CORPORATION COMPONENT | RT0402DRE0710RL |  | G |  |  |  |  |  |  |  |
|  |  |  |  |  | 91 | 61100QT00-012-G |  | RES,10 Ohm,+/-0.5%,1/16W,G,SMD0402 | WALSIN TECHNOLOGY CORPORATION | WF04T10R0DTL |  | G |  |  |  |  |  |  |  |
| Multi | N | ND | Y(4) | 92 | 92 | 610112J00-017-G | - | RES,200 Ohm,+/-1%,1/16W,G,SMD0402 | KOA SPEER ELECTRONICS, INC. | RK73H1ETTP2000F | 1 | G | R1487 |  |  |  |  |  |  |
|  |  |  |  |  | 92 | 610112J00-012-G |  | RES,200 Ohm,+/-1%,1/16W,G,SMD0402 | WALSIN TECHNOLOGY CORPORATION | WR04X2000FTL |  | G |  |  |  |  |  |  |  |
|  |  |  |  |  | 92 | 610112J00-011-G |  | RES,200 Ohm,+/-1%,1/16W,G,SMD0402 | YAGEO CORPORATION COMPONENT | RC0402FR-07200RL |  | G |  |  |  |  |  |  |  |
|  |  |  |  |  | 92 | 610112J00-044-G |  | RES,200 Ohm,+/-1%,1/16W,G,SMD0402 | TA-I TECHNOLOGY CO., LTD. | RM04FTN2000 |  | G |  |  |  |  |  |  |  |
|  |  |  |  |  | 92 | 610112J00-029-G |  | RES,200 Ohm,+/-1%,1/16W,G,SMD0402 | VISHAY ENTER TECHNO LOGY.INC | CRCW0402200RFKED |  | G |  |  |  |  |  |  |  |
|  |  |  |  |  | 92 | 610112J00-024-G |  | RES,200 Ohm,+/-1%,1/16W,G,SMD0402 | PANASONIC INDUSTRIAL CO.,LTD. | ERJ2RKF2000X |  | G |  |  |  |  |  |  |  |
| Multi | N |  | Y(5) | 93 | 93 | 61100LQ00-017-G |  | RES,20KOhm,+/-1%,1/16W,G,SMD0402 | KOA SPEER ELECTRONICS, INC. | RN731ETTP2002F50 | 1 | G | R1488 |  |  |  |  |  |  |
|  |  |  |  |  | 93 | 61100LQ00-011-G |  | RES,20KOhm,+/-1%,1/16W,G,SMD0402 | YAGEO CORPORATION COMPONENT | RT0402FRE0720KL |  | G |  |  |  |  |  |  |  |
|  |  |  |  |  | 93 | 61100LQ00-044-G |  | RES,20KOhm,+/-1%,1/16W,G,SMD0402 | TA-I TECHNOLOGY CO., LTD. | RB04FTS2002 |  | G |  |  |  |  |  |  |  |
|  |  |  |  |  | 93 | 61100LQ00-012-G |  | RES,20KOhm,+/-1%,1/16W,G,SMD0402 | WALSIN TECHNOLOGY CORPORATION | WF04T2002FTL |  | G |  |  |  |  |  |  |  |
| Multi |  |  | Y(4) | 94 | 94 | 610118800-017-G |  | RES,499KOhm,+/-1%,1/8W,G,SMD0805 | KOA SPEER ELECTRONICS, INC. | RK73H2ATTD4993F | 1 | G | R1492 |  |  |  |  |  |  |
|  |  |  |  |  | 94 | 610118800-024-G |  | RES,499KOhm,+/-1%,1/8W,G,SMD0805 | PANASONIC INDUSTRIAL CO.,LTD. | ERJ6ENF4993V |  | G |  |  |  |  |  |  |  |
|  |  |  |  |  | 94 | 610118800-011-G |  | RES,499KOhm,+/-1%,1/8W,G,SMD0805 | YAGEO CORPORATION COMPONENT | RC0805FR-07499KL |  | G |  |  |  |  |  |  |  |
| Multi | ND |  | Y(4) | 95 | 95 | 61011LF00-017-G |  | RES,499KOhm,+/-1%,1/16W,G,SMD0402 | KOA SPEER ELECTRONICS, INC. | RK73H1ETTP4993F | 1 | G | R1493 |  |  |  |  |  |  |
|  |  |  |  |  | 95 | 61011LF00-012-G |  | RES,499KOhm,+/-1%,1/16W,G,SMD0402 | WALSIN TECHNOLOGY CORPORATION | WR04X4993FTL |  | G |  |  |  |  |  |  |  |
|  |  |  |  |  | 95 | 61011LF00-011-G |  | RES,499KOhm,+/-1%,1/16W,G,SMD0402 | YAGEO CORPORATION COMPONENT | RC0402FR-07499KL |  | G |  |  |  |  |  |  |  |
|  |  |  |  |  | 95 | 61011LF00-044-G |  | RES,499KOhm,+/-1%,1/16W,G,SMD0402 | TA-I TECHNOLOGY CO., LTD. | RM04FTN4993 |  | G |  |  |  |  |  |  |  |
| Multi | N | Other | Y(4) | 96 | 96 | 61011CM00-017-G | - | RES,69.8KOhm,+/-1%,1/16W,G,SMD0402 | KOA SPEER ELECTRONICS, INC. | RK73H1ETTP6982F | 3 | G | R1809,R1810,R1812 |  |  |  |  |  |  |
|  |  |  |  |  | 96 | 61011CM00-012-G |  | RES,69.8KOhm,+/-1%,1/16W,G,SMD0402 | WALSIN TECHNOLOGY CORPORATION | WR04X6982FTL |  | G |  |  |  |  |  |  |  |
|  |  |  |  |  | 96 | 61011CM00-011-G |  | RES,69.8KOhm,+/-1%,1/16W,G,SMD0402 | YAGEO CORPORATION COMPONENT | RC0402FR-0769K8L |  | G |  |  |  |  |  |  |  |
|  |  |  |  |  | 96 | 61011CM00-044-G |  | RES,69.8KOhm,+/-1%,1/16W,G,SMD0402 | TA-I TECHNOLOGY CO., LTD. | RM04FTN6982 |  | G |  |  |  |  |  |  |  |
| Multi | ND | ND | Y(4) | 97 | 97 | 610113W00-017-G |  | RES,12.1KOhm,+/-1%,1/16W,G,SMD0402 | KOA SPEER ELECTRONICS, INC. | RK73H1ETTP1212F | 1 | G | R1811 |  |  |  |  |  |  |
|  |  |  |  |  | 97 | 610113W00-012-G |  | RES,12.1KOhm,+/-1%,1/16W,G,SMD0402 | WALSIN TECHNOLOGY CORPORATION | WR04X1212FTL |  | G |  |  |  |  |  |  |  |
|  |  |  |  |  | 97 | 610113W00-011-G |  | RES,12.1KOhm,+/-1%,1/16W,G,SMD0402 | YAGEO CORPORATION COMPONENT | RC0402FR-0712K1L |  | G |  |  |  |  |  |  |  |
|  |  |  |  |  | 97 | 610113W00-044-G |  | RES,12.1KOhm,+/-1%,1/16W,G,SMD0402 | TA-I TECHNOLOGY CO., LTD. | RM04FTN1212 |  | G |  |  |  |  |  |  |  |
| Multi | N |  | Y(5) | 98 | 98 | 61100LV00-017-G |  | RES,10KOhm,+/-1%,1/16W,G,SMD0402 | KOA SPEER ELECTRONICS, INC. | RN731ETTP1002F50 | 4 | G | R1815,R1816,R1817,R1818 |  |  |  |  |  |  |
|  |  |  |  |  | 98 | 61100LV00-011-G |  | RES,10KOhm,+/-1%,1/16W,G,SMD0402 | YAGEO CORPORATION COMPONENT | RT0402FRE0710KL |  | G |  |  |  |  |  |  |  |
|  |  |  |  |  | 98 | 61100LV00-044-G |  | RES,10KOhm,+/-1%,1/16W,G,SMD0402 | TA-I TECHNOLOGY CO., LTD. | RB04FTS1002 |  | G |  |  |  |  |  |  |  |
|  |  |  |  |  | 98 | 61100LV00-012-G |  | RES,10KOhm,+/-1%,1/16W,G,SMD0402 | WALSIN TECHNOLOGY CORPORATION | WF04T1002FTL |  | G |  |  |  |  |  |  |  |
| Multi | ND |  | N | 99 | 99 | 41040HW00-191-G |  | EEPROM,AT24C02D-SSHM-T,1.7~3.6V,2K,I2C,G,SOIC-8,SMD | ATMEL CORPORATION | AT24C02D-SSHM-T | 1 | G | U_FPDB_FRU |  |  |  |  |  |  |
|  |  |  |  |  | 99 | 410401W00-214-G |  | EEPROM,M24C02-WMN6TP,2.5~5.5V,256*8,I2C,G,SOIC-8,SMD | ST MICRO ELECTRONICS,INC | M24C02-WMN6TP |  | G |  |  |  |  |  |  |  |
|  |  |  |  |  | 99 | 41040J500-232-G |  | EEPROM,24AA024T-I/SN,1.7V~5.5V,2K,I2C,G,SOIC-8,SMD | MICROCHIP TECHNOLOGY INC | 24AA024T-I/SN |  | G |  |  |  |  |  |  |  |
| Multi | N | other | Y(1) | 100 | 100 | 320403K00-183-G | - | IC,Temp Sensor,TMP75AIDR,3°C,G,SOIC-8,SMD | TEXAS INSTRUMENTS | TMP75AIDR | 1 | G | U_TMP_R |  |  |  |  |  |  |
|  |  |  |  |  | 100 | 320403Q00-173-G |  | IC,Temp Sensor,DS75S+T&R,3°C,G,SO-8,SMD | MAXIM INTEGRATED PRODUCTS, INC. | DS75S+T&R |  | G |  |  |  |  |  |  |  |
|  |  |  |  |  | 100 | 320405300-214-G |  | IC,Temp Sensor,STLM75M2F,±0.5°C,G,SO-8,SMD | ST MICRO ELECTRONICS,INC | STLM75M2F |  | G |  |  |  |  |  |  |  |
|  |  |  |  |  | 100 | 32040SL00-223-G |  | IC,Temperature Sensor,NCT75DR2G,G,SOIC-8,SMD | ON SEMICONDUCTOR CORP | NCT75DR2G |  | G |  |  |  |  |  |  |  |
|  |  |  |  |  | 100 | 32040FL00-031-G |  | IC,Temperature Sensor,LM75BD,G,SO-8,SMD | NXP SEMICONDUCTORS | LM75BD |  | G |  |  |  |  |  |  |  |
| Multi | ND |  | N | 101 | 101 | 311004800-031-G |  | IC,Translator,PCA9617ADPJ,0.8~5.5V,2.2~5.5V,G,TSSOP-8,SMD | NXP SEMICONDUCTORS | PCA9617ADPJ | 1 | G | U1 |  |  |  |  |  |  |
|  |  |  |  |  | 101 | 311004V00-223-G |  | Logic IC,Translator,PCA9617ADMR2G,Vcca=0.8V~5.5V,Vccb=2.2V~5.5V,102ns,Micro8,8P,G | ON SEMICONDUCTOR CORP | PCA9617ADMR2G |  | G |  |  |  |  |  |  |  |
| Single | ND | ND | Y(1) | 102 | 102 | 310204100-183-G | - | IC,Gate&Inverter,SN74LVC1G14DCKR,1.65~5.5V,G,SC70-5,SMD | TEXAS INSTRUMENTS | SN74LVC1G14DCKR | 1 | G | U2 |  |  |  |  |  |  |
| Single | ND |  | N | 103 | 103 | 32040QL00-09N-G |  | IC,Temp Sensor,A,NCT7904D,N/A,G,LQFP-48,SMD | Nuvoton Technology Corporation | NCT7904D | 2 | G | U3,U4 |  |  |  |  |  |  |
| Single | ND | ND | Y(3) | 104 | 104 | 31010DT00-031-G |  | IC,Gate,74LVC1G02GW,1.65~5.5V,G,SC88A-5,SMD | NXP SEMICONDUCTORS | 74LVC1G02GW | 1 | G | U5 |  |  |  |  |  |  |
| Multi | ND | ND | Y(3) | 105 | 105 | 310502800-031-G |  | IC,Buffer,74LVC1G07GW,1.65~5.5V,G,SOT353-5,SMD | NXP SEMICONDUCTORS | 74LVC1G07GW | 9 | G | U6,U8,U19,U20,U21,U22,U23,U24,U166 |  |  |  |  |  |  |
|  |  |  |  |  | 105 | 31050CU00-131-G |  | IC,Buffer,TC7SZ07FU,1.65~5.5V,G,SSOP-5,SMD | TOSHIBA ELECTRONICS ASIA LTD | TC7SZ07FU |  | G |  |  |  |  |  |  |  |
|  |  |  |  |  | 105 | 310502C00-223-G |  | IC,Buffer,NL17SZ07DFT2G,1.65~5.50V,G,SC-88A/SOT-353-5,SMD | ON SEMICONDUCTOR CORP | NL17SZ07DFT2G |  | G |  |  |  |  |  |  |  |
| Single | ND |  | Y(1) | 106 | 106 | 31010SB00-183-G |  | Logic IC,Gate,ISO1540DR,3V~5.5V,G,SOIC-8,SMD | TEXAS INSTRUMENTS | ISO1540DR | 1 | G | U7 |  |  |  |  |  |  |
| Single | ND | ND | Y(1) | 107 | 107 | 310500U00-183-G | - | IC,Buffer,SN74LVC07APWR,1.65~5V,G,TSSOP-14,SMD | TEXAS INSTRUMENTS | SN74LVC07APWR | 1 | G | U15 |  |  |  |  |  |  |
| Single | N | 1 | Y(3) | 108 | 108 | 320306E00-183-G |  | IC,Comparator,LMV331IDBVR,9mV,G,SOT23-5,SMD | TEXAS INSTRUMENTS | LMV331IDBVR | 2 | G | U16,U17 |  |  |  |  |  |  |
| Single | ND | ND | Y(2) | 109 | 109 | 210204300-031-G |  | IC,NXP,PCA9535PW,G,TSSOP-24,SMD | NXP SEMICONDUCTORS | PCA9535PW | 1 | G | U18 |  |  |  |  |  |  |
| Multi | ND |  | Y(2) | 110 | 110 | 310307T00-031-G |  | IC,Switch,74CBTLV1G125GV,2.3~3.6V,G,SOT753-5,SMD | NXP SEMICONDUCTORS | 74CBTLV1G125GV | 1 | G | U109 |  |  |  |  |  |  |
|  |  |  |  |  | 110 | 310300D00-183-G |  | IC,Switch,SN74CBTLV1G125DBVR,2.3~3.6V,G,SOT23-5,SMD | TEXAS INSTRUMENTS | SN74CBTLV1G125DBVR |  | G |  |  |  |  |  |  |  |
| Multi | ND |  | N | 111 | 111 | 330103N00-426-G |  | IC,Optocoupler,PS2811-1-F3-A,G,SSOP-4,SMD | RENESAS TECHNOLOGY AMERICA INC | PS2811-1-F3-A | 1 | G | U110 |  |  |  |  |  |  |
|  |  |  |  |  | 111 | 330102900-289-G |  | OPTO-IC,ISOL,LTV-217-G,SSOP,4P,G | LITE-ON TECHNOLOGY CORPORATION | LTV-217-G |  | G |  |  |  |  |  |  |  |
|  |  |  |  |  | 111 | 330103T00-029-G |  | IC,Optocoupler,VOS618A-3X001T,G,SSOP-4,SMD | VISHAY ENTER TECHNO LOGY.INC | VOS618A-3X001T |  | G |  |  |  |  |  |  |  |
| Single | ND |  | N | 112 | 112 | 320242H00-226-G |  | IC,Power Controller,LTC2955CDDB-2#TRMPBF,G,DFN-10,SMD | LINEAR TECHNOLOGY CORPORATION | LTC2955CDDB-2#TRMPBF | 1 | G | U165 |  |  |  |  |  |  |
| Multi | ND | ND | Y(1) | 113 | 113 | 71020KL00-100-G | - | OSC,33MHz,+/-50ppm,3.3V,15pF,G,SMD | TXC CORPORATION | 7X33000013 | 2 | G | Y1,Y2 |  |  |  |  |  |  |
|  |  |  |  |  | 113 | 710211800-967-G |  | OSC,33MHz,+/-50ppm,3.3V,15pF,G,SMD | eCERA | FK3300011 |  | G |  |  |  |  |  |  |  |
|  |  |  |  |  | 113 | 710216N00-873-G |  | OSC,33MHz,+/-50ppm,3.3V,15pF,G,SMD | Kyocera | KC3225K33.0000C10E00 |  | G |  |  |  |  |  |  |  |
| Single | ND |  | N | 114 | 114 | 340636700-600-G |  | CONN,Header,Power,2X8,V/T,Whi,4.2mm,G,DIP-16 | FOXCONN TECHNOLOGY CO.,LTD. | HM3508E-HP1 | 1 | G | J_EXP_PWR1 |  |  |  |  |  |  |
| Single | ND |  | N | 115 | 115 | 340636800-600-G |  | CONN,Header,Power,2X9,V/T,Whi,4.2mm,G,DIP-18 | FOXCONN TECHNOLOGY CO.,LTD. | HM3509E-HP1 | 1 | G | J_GPU_PWR1 |  |  |  |  |  |  |
| Multi | ND | ND | N | 116 | 116 | 340612R00-309-G | - | CONN,Jumper,Bla,2.54mm,G,DIP-2 | SAMTEC INC. | SNT-100-BK-G | 1 | G | J_PS_ON_SW(2-3)1 |  |  |  |  |  |  |
|  |  |  |  |  | 116 | 34065L900-GRT-G |  | CONN,jumper,Bla,2.54mm,30u,G,DIP-2 | PINREX TECHNOLOGY CORP. | 201-71-01DB00 |  | G |  |  |  |  |  |  |  |
|  |  |  |  |  | 116 | 34066N500-600-G |  | Header&Socket Connector,SJ0520F-A0,Jumper,2,DIP,PBT,2.54mm,3u",Black,G | FOXCONN TECHNOLOGY CO.,LTD. | SJ0520F-A0 |  | G |  |  |  |  |  |  |  |
| Multi | ND | ND | N | 117 | 117 | 340600S00-600-G | - | CONN,Pin Header,1X3,V/T,Bla,2.54mm,15u,G,DIP-3 | FOXCONN TECHNOLOGY CO.,LTD. | HB1103V | 1 | G | J_PS_ON1 |  |  |  |  |  |  |
|  |  |  |  |  | 117 | 34060WK00-317-G |  | CONN.Pin Header,1X3,V/T,Bla,2.54mm,15u,G,DIP-3 | MOLEX INCORPORATED | 87891-0304 |  | G |  |  |  |  |  |  |  |
|  |  |  |  |  | 117 | 34065R700-GRT-G |  | CONN,Pin Header,1X3,V/T,Bla,2.54mm,15u,G,DIP-3 | PINREX TECHNOLOGY CORP. | 21K-81-03HB01 |  | G |  |  |  |  |  |  |  |
|  |  |  |  |  | 117 | 34065RR00-245-G |  | CONN,Pin Header,1X3,V/T,Bla,2.54mm,15u,G,DIP-3 | AMPHENOL SHANGHAI CORP. | G800305005EU |  | G |  |  |  |  |  |  |  |
| Single | ND |  | N | 118 | 118 | 34044PP00-G78-G |  | CONN,I/O,Terminal Blocks,R/A,Bla,4mm,G,DIP-4 | FCI CONNECTORS HONGKONG LTD. | VP02650700J0G | 1 | G | J_TERMINAL_GND1 |  |  |  |  |  |  |
| Single | ND |  | N | 119 | 119 | 34044PQ00-G78-G |  | CONN,I/O,Terminal Blocks,R/A,Red,4mm,G,DIP-4 | FCI CONNECTORS HONGKONG LTD. | VP02652700J0G | 1 | G | J_TERMINAL_48V1 |  |  |  |  |  |  |
| Single | ND |  | N | 120 | 120 | 3406ANQ00-317-G |  | CONN,Header,Power,V/T,Bla,10mm,30u,G,DIP-8 | MOLEX INCORPORATED | 42819-4213 | 1 | G | J1 |  |  |  |  |  |  |
| Single | ND |  | N | 121 | 121 | 3406ALY00-317-G |  | CONN,Header,Shrouded,2X6,V/T,Bla,2mm,30u,G,SMD-12 | MOLEX INCORPORATED | 87832-5523 | 1 | G | J2 |  |  |  |  |  |  |
| Single | ND |  | N | 122 | 122 | 3406ALW00-317-G |  | CONN,Header,Shrouded,2X5,V/T,Bla,2mm,30u,G,SMD-10 | MOLEX INCORPORATED | 87832-5423 | 1 | G | J3 |  |  |  |  |  |  |
| Single | ND |  | N | 123 | 123 | 3406A1800-317-G |  | CONN,Header,WTB,1X8,V/T,Bla,2.54mm,G,DIP-8 | MOLEX INCORPORATED | 171856-0108 | 6 | G | J4,J5,J6,J7,J8,J9 |  |  |  |  |  |  |
